FILE_TYPE = MACRO_DRAWING;
SET COLOR_WIRE YELLOW;
SET COLOR_PROP ORANGE;
SET COLOR_DOT WHITE;
SET COLOR_ARC YELLOW;
SET COLOR_BODY GREEN;
SET COLOR_NOTE PURPLE;
SET PROP_DISPLAY VALUE;
SET PAGE_NUMBER P227;
FORCEADD UNIVERSAL_GND..1
(-14825 -2675);
FORCEPROP 3 LASTPIN (-14825 -2625) SIG_NAME GND\g
J 0
(-14815 -2615);
DISPLAY 0.659574 (-14815 -2615);
PAINT MONO (-14815 -2615);
DISPLAY INVISIBLE (-14815 -2615);
FORCEPROP 2 LAST CDS_LIB logical_power
J 0
(-14825 -2675);
DISPLAY INVISIBLE (-14825 -2675);
FORCEPROP 1 LAST HDL_POWER GND
J 1
(-14800 -2750);
DISPLAY 0.702128 (-14800 -2750);
PAINT GREEN (-14800 -2750);
DISPLAY INVISIBLE (-14800 -2750);
FORCEPROP 1 LAST PATH I1
J 0
(-14750 -2675);
DISPLAY 0.872340 (-14750 -2675);
PAINT AQUA (-14750 -2675);
DISPLAY INVISIBLE (-14750 -2675);
FORCEADD OFFPAGE..5
(-14325 -1125);
FORCEPROP 2 LAST $XR0 223 
J 0
(-14580 -1125);
DISPLAY 0.638298 (-14580 -1125);
PAINT MONO (-14580 -1125);
FORCEPROP 1 LAST OFFPAGE TRUE
J 0
(-14000 -1250);
DISPLAY 0.872340 (-14000 -1250);
PAINT GREEN (-14000 -1250);
DISPLAY INVISIBLE (-14000 -1250);
FORCEPROP 1 LAST COMMENT_BODY TRUE
J 0
(-14225 -1200);
DISPLAY 0.872340 (-14225 -1200);
PAINT PEACH (-14225 -1200);
DISPLAY INVISIBLE (-14225 -1200);
FORCEPROP 2 LAST CDS_LIB standard
J 0
(-14325 -1125);
PAINT MONO (-14325 -1125);
DISPLAY INVISIBLE (-14325 -1125);
FORCEPROP 2 LAST PATH I10
J 0
(-14575 -1075);
DISPLAY 1.021277 (-14575 -1075);
DISPLAY INVISIBLE (-14575 -1075);
FORCEADD Q_RES..1
(-13275 1275);
FORCEPROP 1 LAST PART_NUMBER CS03322FB03
J 0
(-13375 925);
DISPLAY 0.404255 (-13375 925);
DISPLAY INVISIBLE (-13375 925);
FORCEPROP 1 LAST WATTAGE 1/16W
J 2
(-13150 975);
DISPLAY 0.404255 (-13150 975);
FORCEPROP 1 LAST VALUE 33.2
J 2
(-13075 1275);
DISPLAY 0.510638 (-13075 1275);
FORCEPROP 1 LAST PACK_TYPE 0402LF
J 0
(-13375 975);
DISPLAY 0.404255 (-13375 975);
FORCEPROP 1 LAST TOLERANCE 1%
J 0
(-13050 1275);
DISPLAY 0.510638 (-13050 1275);
FORCEPROP 1 LAST MATERIAL CHIP
J 0
(-12975 1275);
DISPLAY 0.510638 (-12975 1275);
FORCEPROP 1 LAST $LOCATION R2419
J 0
(-13500 1275);
DISPLAY 0.638298 (-13500 1275);
FORCEPROP 1 LASTPIN (-13375 1275) $PN 1
J 0
(-13363 1287);
DISPLAY 0.787234 (-13363 1287);
PAINT MONO (-13363 1287);
FORCEPROP 1 LASTPIN (-13175 1275) $PN 2
J 0
(-13213 1287);
DISPLAY 0.787234 (-13213 1287);
PAINT MONO (-13213 1287);
FORCEPROP 2 LAST CDS_LIB pure_quanta
J 0
(-13275 1275);
DISPLAY INVISIBLE (-13275 1275);
FORCEPROP 1 LAST PATH I100
J 0
(-13325 1425);
DISPLAY 0.978723 (-13325 1425);
PAINT WHITE (-13325 1425);
DISPLAY INVISIBLE (-13325 1425);
FORCEPROP 0 LAST CDS_LOCATION R2419
J 0
(-13175 1400);
DISPLAY 1.021277 (-13175 1400);
DISPLAY INVISIBLE (-13175 1400);
FORCEPROP 0 LAST $SEC 1
J 0
(-13175 1400);
DISPLAY 0.680851 (-13175 1400);
PAINT MONO (-13175 1400);
DISPLAY INVISIBLE (-13175 1400);
FORCEPROP 0 LAST CDS_SEC 1
J 0
(-13175 1400);
DISPLAY 1.021277 (-13175 1400);
DISPLAY INVISIBLE (-13175 1400);
FORCEADD Q_RES..1
(-13275 1375);
FORCEPROP 1 LAST PART_NUMBER CS03322FB03
J 0
(-13400 1425);
DISPLAY 0.404255 (-13400 1425);
DISPLAY INVISIBLE (-13400 1425);
FORCEPROP 1 LAST VALUE 33.2
J 2
(-13075 1375);
DISPLAY 0.510638 (-13075 1375);
FORCEPROP 1 LAST TOLERANCE 1%
J 0
(-13050 1375);
DISPLAY 0.510638 (-13050 1375);
FORCEPROP 1 LAST MATERIAL CHIP
J 0
(-12975 1375);
DISPLAY 0.510638 (-12975 1375);
FORCEPROP 1 LAST $LOCATION R3238
J 0
(-13500 1375);
DISPLAY 0.638298 (-13500 1375);
FORCEPROP 1 LASTPIN (-13375 1375) $PN 1
J 0
(-13363 1387);
DISPLAY 0.787234 (-13363 1387);
PAINT MONO (-13363 1387);
FORCEPROP 1 LASTPIN (-13175 1375) $PN 2
J 0
(-13213 1387);
DISPLAY 0.787234 (-13213 1387);
PAINT MONO (-13213 1387);
FORCEPROP 2 LAST CDS_LIB pure_quanta
J 0
(-13275 1375);
DISPLAY INVISIBLE (-13275 1375);
FORCEPROP 1 LAST WATTAGE 1/16W
J 2
(-13175 1475);
DISPLAY 0.404255 (-13175 1475);
DISPLAY INVISIBLE (-13175 1475);
FORCEPROP 1 LAST PACK_TYPE 0402LF
J 0
(-13400 1475);
DISPLAY 0.404255 (-13400 1475);
DISPLAY INVISIBLE (-13400 1475);
FORCEPROP 1 LAST PATH I101
J 0
(-13325 1525);
DISPLAY 0.978723 (-13325 1525);
PAINT WHITE (-13325 1525);
DISPLAY INVISIBLE (-13325 1525);
FORCEPROP 0 LAST CDS_LOCATION R3238
J 0
(-13325 1475);
DISPLAY 1.021277 (-13325 1475);
DISPLAY INVISIBLE (-13325 1475);
FORCEPROP 0 LAST $SEC 1
J 0
(-13325 1475);
DISPLAY 0.680851 (-13325 1475);
PAINT MONO (-13325 1475);
DISPLAY INVISIBLE (-13325 1475);
FORCEPROP 0 LAST CDS_SEC 1
J 0
(-13325 1475);
DISPLAY 1.021277 (-13325 1475);
DISPLAY INVISIBLE (-13325 1475);
FORCEADD Q_RES..1
(-13275 1325);
FORCEPROP 1 LAST PART_NUMBER CS03322FB03
J 0
(-13400 1375);
DISPLAY 0.404255 (-13400 1375);
DISPLAY INVISIBLE (-13400 1375);
FORCEPROP 1 LAST VALUE 33.2
J 2
(-13075 1325);
DISPLAY 0.510638 (-13075 1325);
FORCEPROP 1 LAST TOLERANCE 1%
J 0
(-13050 1325);
DISPLAY 0.510638 (-13050 1325);
FORCEPROP 1 LAST MATERIAL CHIP
J 0
(-12975 1325);
DISPLAY 0.510638 (-12975 1325);
FORCEPROP 1 LAST $LOCATION R3239
J 0
(-13500 1325);
DISPLAY 0.638298 (-13500 1325);
FORCEPROP 1 LASTPIN (-13375 1325) $PN 1
J 0
(-13363 1337);
DISPLAY 0.787234 (-13363 1337);
PAINT MONO (-13363 1337);
FORCEPROP 1 LASTPIN (-13175 1325) $PN 2
J 0
(-13213 1337);
DISPLAY 0.787234 (-13213 1337);
PAINT MONO (-13213 1337);
FORCEPROP 2 LAST CDS_LIB pure_quanta
J 0
(-13275 1325);
DISPLAY INVISIBLE (-13275 1325);
FORCEPROP 1 LAST WATTAGE 1/16W
J 2
(-13175 1425);
DISPLAY 0.404255 (-13175 1425);
DISPLAY INVISIBLE (-13175 1425);
FORCEPROP 1 LAST PACK_TYPE 0402LF
J 0
(-13400 1425);
DISPLAY 0.404255 (-13400 1425);
DISPLAY INVISIBLE (-13400 1425);
FORCEPROP 1 LAST PATH I102
J 0
(-13325 1475);
DISPLAY 0.978723 (-13325 1475);
PAINT WHITE (-13325 1475);
DISPLAY INVISIBLE (-13325 1475);
FORCEPROP 0 LAST CDS_LOCATION R3239
J 0
(-13325 1425);
DISPLAY 1.021277 (-13325 1425);
DISPLAY INVISIBLE (-13325 1425);
FORCEPROP 0 LAST $SEC 1
J 0
(-13325 1425);
DISPLAY 0.680851 (-13325 1425);
PAINT MONO (-13325 1425);
DISPLAY INVISIBLE (-13325 1425);
FORCEPROP 0 LAST CDS_SEC 1
J 0
(-13325 1425);
DISPLAY 1.021277 (-13325 1425);
DISPLAY INVISIBLE (-13325 1425);
FORCEADD OFFPAGE..5
(-12450 -425);
FORCEPROP 2 LAST $XR0 248 
J 0
(-12705 -425);
DISPLAY 0.638298 (-12705 -425);
PAINT MONO (-12705 -425);
FORCEPROP 2 LAST CDS_LIB standard
J 0
(-12450 -425);
DISPLAY INVISIBLE (-12450 -425);
FORCEPROP 1 LAST OFFPAGE TRUE
J 0
(-12125 -550);
DISPLAY 0.872340 (-12125 -550);
PAINT GREEN (-12125 -550);
DISPLAY INVISIBLE (-12125 -550);
FORCEPROP 1 LAST COMMENT_BODY TRUE
J 0
(-12350 -500);
DISPLAY 0.872340 (-12350 -500);
PAINT PEACH (-12350 -500);
DISPLAY INVISIBLE (-12350 -500);
FORCEPROP 2 LAST PATH I103
J 0
(-12700 -375);
DISPLAY 1.021277 (-12700 -375);
DISPLAY INVISIBLE (-12700 -375);
FORCEADD OFFPAGE..5
(-12450 -475);
FORCEPROP 2 LAST $XR0 248 
J 0
(-12705 -475);
DISPLAY 0.638298 (-12705 -475);
PAINT MONO (-12705 -475);
FORCEPROP 2 LAST CDS_LIB standard
J 0
(-12450 -475);
DISPLAY INVISIBLE (-12450 -475);
FORCEPROP 1 LAST OFFPAGE TRUE
J 0
(-12125 -600);
DISPLAY 0.872340 (-12125 -600);
PAINT GREEN (-12125 -600);
DISPLAY INVISIBLE (-12125 -600);
FORCEPROP 1 LAST COMMENT_BODY TRUE
J 0
(-12350 -550);
DISPLAY 0.872340 (-12350 -550);
PAINT PEACH (-12350 -550);
DISPLAY INVISIBLE (-12350 -550);
FORCEPROP 2 LAST PATH I104
J 0
(-12700 -425);
DISPLAY 1.021277 (-12700 -425);
DISPLAY INVISIBLE (-12700 -425);
FORCEADD OFFPAGE..5
(-12450 -375);
FORCEPROP 2 LAST $XR0 248 
J 0
(-12705 -375);
DISPLAY 0.638298 (-12705 -375);
PAINT MONO (-12705 -375);
FORCEPROP 2 LAST CDS_LIB standard
J 0
(-12450 -375);
DISPLAY INVISIBLE (-12450 -375);
FORCEPROP 1 LAST COMMENT_BODY TRUE
J 0
(-12350 -450);
DISPLAY 0.872340 (-12350 -450);
PAINT PEACH (-12350 -450);
DISPLAY INVISIBLE (-12350 -450);
FORCEPROP 1 LAST OFFPAGE TRUE
J 0
(-12125 -500);
DISPLAY 0.872340 (-12125 -500);
PAINT GREEN (-12125 -500);
DISPLAY INVISIBLE (-12125 -500);
FORCEPROP 2 LAST PATH I105
J 0
(-12700 -325);
DISPLAY 1.021277 (-12700 -325);
DISPLAY INVISIBLE (-12700 -325);
FORCEADD OFFPAGE..6
(-12450 -125);
FORCEPROP 2 LAST $XR0 241 
J 0
(-12760 -125);
DISPLAY 0.638298 (-12760 -125);
PAINT MONO (-12760 -125);
FORCEPROP 2 LAST $XR1 245 
J 0
(-12880 -125);
DISPLAY 0.638298 (-12880 -125);
PAINT MONO (-12880 -125);
FORCEPROP 1 LAST OFFPAGE TRUE
J 0
(-12125 -250);
DISPLAY 0.872340 (-12125 -250);
PAINT GREEN (-12125 -250);
DISPLAY INVISIBLE (-12125 -250);
FORCEPROP 1 LAST COMMENT_BODY TRUE
J 0
(-12350 -200);
DISPLAY 0.872340 (-12350 -200);
PAINT PEACH (-12350 -200);
DISPLAY INVISIBLE (-12350 -200);
FORCEPROP 2 LAST CDS_LIB standard
J 0
(-12450 -125);
DISPLAY INVISIBLE (-12450 -125);
FORCEPROP 2 LAST PATH I106
J 0
(-12750 -75);
DISPLAY 1.021277 (-12750 -75);
DISPLAY INVISIBLE (-12750 -75);
FORCEADD OFFPAGE..6
(-12450 -175);
FORCEPROP 2 LAST $XR0 241 
J 0
(-12760 -175);
DISPLAY 0.638298 (-12760 -175);
PAINT MONO (-12760 -175);
FORCEPROP 2 LAST $XR1 245 
J 0
(-12880 -175);
DISPLAY 0.638298 (-12880 -175);
PAINT MONO (-12880 -175);
FORCEPROP 1 LAST COMMENT_BODY TRUE
J 0
(-12350 -250);
DISPLAY 0.872340 (-12350 -250);
PAINT PEACH (-12350 -250);
DISPLAY INVISIBLE (-12350 -250);
FORCEPROP 1 LAST OFFPAGE TRUE
J 0
(-12125 -300);
DISPLAY 0.872340 (-12125 -300);
PAINT GREEN (-12125 -300);
DISPLAY INVISIBLE (-12125 -300);
FORCEPROP 2 LAST CDS_LIB standard
J 0
(-12450 -175);
PAINT MONO (-12450 -175);
DISPLAY INVISIBLE (-12450 -175);
FORCEPROP 2 LAST PATH I107
J 0
(-12750 -125);
DISPLAY 1.021277 (-12750 -125);
DISPLAY INVISIBLE (-12750 -125);
FORCEADD OFFPAGE..6
(-12450 225);
FORCEPROP 2 LAST $XR0 231 
J 0
(-12760 225);
DISPLAY 0.638298 (-12760 225);
PAINT MONO (-12760 225);
FORCEPROP 2 LAST CDS_LIB standard
J 0
(-12450 225);
DISPLAY INVISIBLE (-12450 225);
FORCEPROP 1 LAST OFFPAGE TRUE
J 0
(-12125 100);
DISPLAY 0.872340 (-12125 100);
PAINT GREEN (-12125 100);
DISPLAY INVISIBLE (-12125 100);
FORCEPROP 1 LAST COMMENT_BODY TRUE
J 0
(-12350 150);
DISPLAY 0.872340 (-12350 150);
PAINT PEACH (-12350 150);
DISPLAY INVISIBLE (-12350 150);
FORCEPROP 2 LAST PATH I108
J 0
(-12750 275);
DISPLAY 1.021277 (-12750 275);
DISPLAY INVISIBLE (-12750 275);
FORCEADD OFFPAGE..6
(-12450 275);
FORCEPROP 2 LAST $XR0 231 
J 0
(-12760 275);
DISPLAY 0.638298 (-12760 275);
PAINT MONO (-12760 275);
FORCEPROP 1 LAST COMMENT_BODY TRUE
J 0
(-12350 200);
DISPLAY 0.872340 (-12350 200);
PAINT PEACH (-12350 200);
DISPLAY INVISIBLE (-12350 200);
FORCEPROP 1 LAST OFFPAGE TRUE
J 0
(-12125 150);
DISPLAY 0.872340 (-12125 150);
PAINT GREEN (-12125 150);
DISPLAY INVISIBLE (-12125 150);
FORCEPROP 2 LAST CDS_LIB standard
J 0
(-12450 275);
DISPLAY INVISIBLE (-12450 275);
FORCEPROP 2 LAST PATH I109
J 0
(-12750 325);
DISPLAY 1.021277 (-12750 325);
DISPLAY INVISIBLE (-12750 325);
FORCEADD OFFPAGE..5
(-14325 -1075);
FORCEPROP 2 LAST $XR0 223 
J 0
(-14580 -1075);
DISPLAY 0.638298 (-14580 -1075);
PAINT MONO (-14580 -1075);
FORCEPROP 2 LAST CDS_LIB standard
J 0
(-14325 -1075);
DISPLAY INVISIBLE (-14325 -1075);
FORCEPROP 1 LAST COMMENT_BODY TRUE
J 0
(-14225 -1150);
DISPLAY 0.872340 (-14225 -1150);
PAINT PEACH (-14225 -1150);
DISPLAY INVISIBLE (-14225 -1150);
FORCEPROP 1 LAST OFFPAGE TRUE
J 0
(-14000 -1200);
DISPLAY 0.872340 (-14000 -1200);
PAINT GREEN (-14000 -1200);
DISPLAY INVISIBLE (-14000 -1200);
FORCEPROP 2 LAST PATH I11
J 0
(-14575 -1025);
DISPLAY 1.021277 (-14575 -1025);
DISPLAY INVISIBLE (-14575 -1025);
FORCEADD OFFPAGE..5
(-12450 375);
FORCEPROP 2 LAST $XR0 181 
J 0
(-12705 375);
DISPLAY 0.638298 (-12705 375);
PAINT MONO (-12705 375);
FORCEPROP 1 LAST OFFPAGE TRUE
J 0
(-12125 250);
DISPLAY 0.872340 (-12125 250);
PAINT GREEN (-12125 250);
DISPLAY INVISIBLE (-12125 250);
FORCEPROP 2 LAST CDS_LIB standard
J 0
(-12450 375);
DISPLAY INVISIBLE (-12450 375);
FORCEPROP 1 LAST COMMENT_BODY TRUE
J 0
(-12350 300);
DISPLAY 0.872340 (-12350 300);
PAINT PEACH (-12350 300);
DISPLAY INVISIBLE (-12350 300);
FORCEPROP 2 LAST PATH I110
J 0
(-12700 425);
DISPLAY 1.021277 (-12700 425);
DISPLAY INVISIBLE (-12700 425);
FORCEADD OFFPAGE..5
(-12450 425);
FORCEPROP 2 LAST $XR0 181 
J 0
(-12705 425);
DISPLAY 0.638298 (-12705 425);
PAINT MONO (-12705 425);
FORCEPROP 1 LAST OFFPAGE TRUE
J 0
(-12125 300);
DISPLAY 0.872340 (-12125 300);
PAINT GREEN (-12125 300);
DISPLAY INVISIBLE (-12125 300);
FORCEPROP 2 LAST CDS_LIB standard
J 0
(-12450 425);
DISPLAY INVISIBLE (-12450 425);
FORCEPROP 1 LAST COMMENT_BODY TRUE
J 0
(-12350 350);
DISPLAY 0.872340 (-12350 350);
PAINT PEACH (-12350 350);
DISPLAY INVISIBLE (-12350 350);
FORCEPROP 2 LAST PATH I111
J 0
(-12700 475);
DISPLAY 1.021277 (-12700 475);
DISPLAY INVISIBLE (-12700 475);
FORCEADD OFFPAGE..1
(-12450 525);
FORCEPROP 2 LAST $XR0 181 
J 0
(-12732 525);
DISPLAY 0.638298 (-12732 525);
PAINT MONO (-12732 525);
FORCEPROP 2 LAST CDS_LIB standard
J 0
(-12450 525);
PAINT MONO (-12450 525);
DISPLAY INVISIBLE (-12450 525);
FORCEPROP 1 LAST OFFPAGE TRUE
J 0
(-12125 400);
DISPLAY 0.872340 (-12125 400);
PAINT GREEN (-12125 400);
DISPLAY INVISIBLE (-12125 400);
FORCEPROP 1 LAST COMMENT_BODY TRUE
J 0
(-12325 425);
DISPLAY 0.872340 (-12325 425);
PAINT PEACH (-12325 425);
DISPLAY INVISIBLE (-12325 425);
FORCEPROP 2 LAST PATH I112
J 0
(-12725 575);
DISPLAY 1.021277 (-12725 575);
DISPLAY INVISIBLE (-12725 575);
FORCEADD OFFPAGE..1
(-12450 575);
FORCEPROP 2 LAST $XR0 181 
J 0
(-12732 575);
DISPLAY 0.638298 (-12732 575);
PAINT MONO (-12732 575);
FORCEPROP 2 LAST CDS_LIB standard
J 0
(-12450 575);
PAINT MONO (-12450 575);
DISPLAY INVISIBLE (-12450 575);
FORCEPROP 1 LAST OFFPAGE TRUE
J 0
(-12125 450);
DISPLAY 0.872340 (-12125 450);
PAINT GREEN (-12125 450);
DISPLAY INVISIBLE (-12125 450);
FORCEPROP 1 LAST COMMENT_BODY TRUE
J 0
(-12325 475);
DISPLAY 0.872340 (-12325 475);
PAINT PEACH (-12325 475);
DISPLAY INVISIBLE (-12325 475);
FORCEPROP 2 LAST PATH I113
J 0
(-12725 625);
DISPLAY 1.021277 (-12725 625);
DISPLAY INVISIBLE (-12725 625);
FORCEADD OFFPAGE..6
(-12450 925);
FORCEPROP 2 LAST $XR0 234 
J 0
(-12760 925);
DISPLAY 0.638298 (-12760 925);
PAINT MONO (-12760 925);
FORCEPROP 2 LAST $XR1 241 
J 0
(-12880 925);
DISPLAY 0.638298 (-12880 925);
PAINT MONO (-12880 925);
FORCEPROP 1 LAST OFFPAGE TRUE
J 0
(-12125 800);
DISPLAY 0.872340 (-12125 800);
PAINT GREEN (-12125 800);
DISPLAY INVISIBLE (-12125 800);
FORCEPROP 1 LAST COMMENT_BODY TRUE
J 0
(-12350 850);
DISPLAY 0.872340 (-12350 850);
PAINT PEACH (-12350 850);
DISPLAY INVISIBLE (-12350 850);
FORCEPROP 2 LAST CDS_LIB standard
J 0
(-12450 925);
PAINT MONO (-12450 925);
DISPLAY INVISIBLE (-12450 925);
FORCEPROP 2 LAST PATH I114
J 0
(-12750 975);
DISPLAY 1.021277 (-12750 975);
DISPLAY INVISIBLE (-12750 975);
FORCEADD OFFPAGE..6
(-12450 975);
FORCEPROP 2 LAST $XR0 241 
J 0
(-12760 975);
DISPLAY 0.638298 (-12760 975);
PAINT MONO (-12760 975);
FORCEPROP 2 LAST $XR1 234 
J 0
(-12880 975);
DISPLAY 0.638298 (-12880 975);
PAINT MONO (-12880 975);
FORCEPROP 1 LAST COMMENT_BODY TRUE
J 0
(-12350 900);
DISPLAY 0.872340 (-12350 900);
PAINT PEACH (-12350 900);
DISPLAY INVISIBLE (-12350 900);
FORCEPROP 1 LAST OFFPAGE TRUE
J 0
(-12125 850);
DISPLAY 0.872340 (-12125 850);
PAINT GREEN (-12125 850);
DISPLAY INVISIBLE (-12125 850);
FORCEPROP 2 LAST CDS_LIB standard
J 0
(-12450 975);
DISPLAY INVISIBLE (-12450 975);
FORCEPROP 2 LAST PATH I115
J 0
(-12750 1025);
DISPLAY 1.021277 (-12750 1025);
DISPLAY INVISIBLE (-12750 1025);
FORCEADD OFFPAGE..5
(-12450 1525);
FORCEPROP 2 LAST $XR0 215 
J 0
(-12705 1525);
DISPLAY 0.638298 (-12705 1525);
PAINT MONO (-12705 1525);
FORCEPROP 1 LAST OFFPAGE TRUE
J 0
(-12125 1400);
DISPLAY 0.872340 (-12125 1400);
PAINT GREEN (-12125 1400);
DISPLAY INVISIBLE (-12125 1400);
FORCEPROP 1 LAST COMMENT_BODY TRUE
J 0
(-12350 1450);
DISPLAY 0.872340 (-12350 1450);
PAINT PEACH (-12350 1450);
DISPLAY INVISIBLE (-12350 1450);
FORCEPROP 2 LAST CDS_LIB standard
J 0
(-12450 1525);
DISPLAY INVISIBLE (-12450 1525);
FORCEPROP 2 LAST PATH I116
J 0
(-12700 1575);
DISPLAY 1.021277 (-12700 1575);
DISPLAY INVISIBLE (-12700 1575);
FORCEADD OFFPAGE..2
(-13600 2375);
FORCEPROP 2 LAST $XR0 240 
J 0
(-13411 2375);
DISPLAY 0.638298 (-13411 2375);
PAINT MONO (-13411 2375);
FORCEPROP 2 LAST CDS_LIB standard
J 0
(-13600 2375);
PAINT MONO (-13600 2375);
DISPLAY INVISIBLE (-13600 2375);
FORCEPROP 1 LAST OFFPAGE TRUE
J 0
(-13275 2250);
DISPLAY 0.872340 (-13275 2250);
DISPLAY INVISIBLE (-13275 2250);
FORCEPROP 1 LAST COMMENT_BODY TRUE
J 0
(-13645 2280);
DISPLAY 0.872340 (-13645 2280);
PAINT GREEN (-13645 2280);
DISPLAY INVISIBLE (-13645 2280);
FORCEPROP 2 LAST PATH I117
J 0
(-13400 2425);
DISPLAY 1.021277 (-13400 2425);
DISPLAY INVISIBLE (-13400 2425);
FORCEADD OFFPAGE..6
(-12450 1625);
FORCEPROP 2 LAST $XR0 241 
J 0
(-12760 1625);
DISPLAY 0.638298 (-12760 1625);
PAINT MONO (-12760 1625);
FORCEPROP 2 LAST CDS_LIB standard
J 0
(-12450 1625);
DISPLAY INVISIBLE (-12450 1625);
FORCEPROP 1 LAST COMMENT_BODY TRUE
J 0
(-12350 1550);
DISPLAY 0.872340 (-12350 1550);
PAINT PEACH (-12350 1550);
DISPLAY INVISIBLE (-12350 1550);
FORCEPROP 1 LAST OFFPAGE TRUE
J 0
(-12125 1500);
DISPLAY 0.872340 (-12125 1500);
PAINT GREEN (-12125 1500);
DISPLAY INVISIBLE (-12125 1500);
FORCEPROP 2 LAST PATH I118
J 0
(-12750 1675);
DISPLAY 1.021277 (-12750 1675);
DISPLAY INVISIBLE (-12750 1675);
FORCEADD OFFPAGE..6
(-12450 1675);
FORCEPROP 2 LAST $XR0 241 
J 0
(-12760 1675);
DISPLAY 0.638298 (-12760 1675);
PAINT MONO (-12760 1675);
FORCEPROP 1 LAST COMMENT_BODY TRUE
J 0
(-12350 1600);
DISPLAY 0.872340 (-12350 1600);
PAINT PEACH (-12350 1600);
DISPLAY INVISIBLE (-12350 1600);
FORCEPROP 1 LAST OFFPAGE TRUE
J 0
(-12125 1550);
DISPLAY 0.872340 (-12125 1550);
PAINT GREEN (-12125 1550);
DISPLAY INVISIBLE (-12125 1550);
FORCEPROP 2 LAST CDS_LIB standard
J 0
(-12450 1675);
DISPLAY INVISIBLE (-12450 1675);
FORCEPROP 2 LAST PATH I119
J 0
(-12750 1725);
DISPLAY 1.021277 (-12750 1725);
DISPLAY INVISIBLE (-12750 1725);
FORCEADD OFFPAGE..6
(-14575 -575);
FORCEPROP 2 LAST $XR0 234 
J 0
(-14855 -575);
DISPLAY 0.638298 (-14855 -575);
PAINT MONO (-14855 -575);
FORCEPROP 2 LAST $XR1 241 
J 0
(-14975 -575);
DISPLAY 0.638298 (-14975 -575);
PAINT MONO (-14975 -575);
FORCEPROP 2 LAST CDS_LIB standard
J 0
(-14575 -575);
DISPLAY INVISIBLE (-14575 -575);
FORCEPROP 1 LAST OFFPAGE TRUE
J 0
(-14250 -700);
DISPLAY 0.872340 (-14250 -700);
PAINT GREEN (-14250 -700);
DISPLAY INVISIBLE (-14250 -700);
FORCEPROP 1 LAST COMMENT_BODY TRUE
J 0
(-14475 -650);
DISPLAY 0.872340 (-14475 -650);
PAINT PEACH (-14475 -650);
DISPLAY INVISIBLE (-14475 -650);
FORCEPROP 2 LAST PATH I12
J 0
(-14850 -525);
DISPLAY 1.021277 (-14850 -525);
DISPLAY INVISIBLE (-14850 -525);
FORCEADD OFFPAGE..6
(-12450 1775);
FORCEPROP 2 LAST $XR0 241 
J 0
(-12760 1775);
DISPLAY 0.638298 (-12760 1775);
PAINT MONO (-12760 1775);
FORCEPROP 1 LAST COMMENT_BODY TRUE
J 0
(-12350 1700);
DISPLAY 0.872340 (-12350 1700);
PAINT PEACH (-12350 1700);
DISPLAY INVISIBLE (-12350 1700);
FORCEPROP 1 LAST OFFPAGE TRUE
J 0
(-12125 1650);
DISPLAY 0.872340 (-12125 1650);
PAINT GREEN (-12125 1650);
DISPLAY INVISIBLE (-12125 1650);
FORCEPROP 2 LAST CDS_LIB standard
J 0
(-12450 1775);
DISPLAY INVISIBLE (-12450 1775);
FORCEPROP 2 LAST PATH I120
J 0
(-12750 1825);
DISPLAY 1.021277 (-12750 1825);
DISPLAY INVISIBLE (-12750 1825);
FORCEADD OFFPAGE..6
(-12450 1725);
FORCEPROP 2 LAST $XR0 241 
J 0
(-12760 1725);
DISPLAY 0.638298 (-12760 1725);
PAINT MONO (-12760 1725);
FORCEPROP 2 LAST CDS_LIB standard
J 0
(-12450 1725);
DISPLAY INVISIBLE (-12450 1725);
FORCEPROP 1 LAST COMMENT_BODY TRUE
J 0
(-12350 1650);
DISPLAY 0.872340 (-12350 1650);
PAINT PEACH (-12350 1650);
DISPLAY INVISIBLE (-12350 1650);
FORCEPROP 1 LAST OFFPAGE TRUE
J 0
(-12125 1600);
DISPLAY 0.872340 (-12125 1600);
PAINT GREEN (-12125 1600);
DISPLAY INVISIBLE (-12125 1600);
FORCEPROP 2 LAST PATH I121
J 0
(-12750 1775);
DISPLAY 1.021277 (-12750 1775);
DISPLAY INVISIBLE (-12750 1775);
FORCEADD OFFPAGE..6
(-12450 1875);
FORCEPROP 2 LAST $XR0 241 
J 0
(-12760 1875);
DISPLAY 0.638298 (-12760 1875);
PAINT MONO (-12760 1875);
FORCEPROP 1 LAST COMMENT_BODY TRUE
J 0
(-12350 1800);
DISPLAY 0.872340 (-12350 1800);
PAINT PEACH (-12350 1800);
DISPLAY INVISIBLE (-12350 1800);
FORCEPROP 1 LAST OFFPAGE TRUE
J 0
(-12125 1750);
DISPLAY 0.872340 (-12125 1750);
PAINT GREEN (-12125 1750);
DISPLAY INVISIBLE (-12125 1750);
FORCEPROP 2 LAST CDS_LIB standard
J 0
(-12450 1875);
DISPLAY INVISIBLE (-12450 1875);
FORCEPROP 2 LAST PATH I122
J 0
(-12750 1925);
DISPLAY 1.021277 (-12750 1925);
DISPLAY INVISIBLE (-12750 1925);
FORCEADD OFFPAGE..6
(-12450 1825);
FORCEPROP 2 LAST $XR0 241 
J 0
(-12760 1825);
DISPLAY 0.638298 (-12760 1825);
PAINT MONO (-12760 1825);
FORCEPROP 2 LAST CDS_LIB standard
J 0
(-12450 1825);
PAINT MONO (-12450 1825);
DISPLAY INVISIBLE (-12450 1825);
FORCEPROP 1 LAST OFFPAGE TRUE
J 0
(-12125 1700);
DISPLAY 0.872340 (-12125 1700);
PAINT GREEN (-12125 1700);
DISPLAY INVISIBLE (-12125 1700);
FORCEPROP 1 LAST COMMENT_BODY TRUE
J 0
(-12350 1750);
DISPLAY 0.872340 (-12350 1750);
PAINT PEACH (-12350 1750);
DISPLAY INVISIBLE (-12350 1750);
FORCEPROP 2 LAST PATH I123
J 0
(-12750 1875);
DISPLAY 1.021277 (-12750 1875);
DISPLAY INVISIBLE (-12750 1875);
FORCEADD OFFPAGE..6
(-12450 1925);
FORCEPROP 2 LAST $XR0 241 
J 0
(-12760 1925);
DISPLAY 0.638298 (-12760 1925);
PAINT MONO (-12760 1925);
FORCEPROP 2 LAST CDS_LIB standard
J 0
(-12450 1925);
PAINT MONO (-12450 1925);
DISPLAY INVISIBLE (-12450 1925);
FORCEPROP 1 LAST OFFPAGE TRUE
J 0
(-12125 1800);
DISPLAY 0.872340 (-12125 1800);
PAINT GREEN (-12125 1800);
DISPLAY INVISIBLE (-12125 1800);
FORCEPROP 1 LAST COMMENT_BODY TRUE
J 0
(-12350 1850);
DISPLAY 0.872340 (-12350 1850);
PAINT PEACH (-12350 1850);
DISPLAY INVISIBLE (-12350 1850);
FORCEPROP 2 LAST PATH I124
J 0
(-12750 1975);
DISPLAY 1.021277 (-12750 1975);
DISPLAY INVISIBLE (-12750 1975);
FORCEADD OFFPAGE..6
(-12450 1975);
FORCEPROP 2 LAST $XR0 241 
J 0
(-12760 1975);
DISPLAY 0.638298 (-12760 1975);
PAINT MONO (-12760 1975);
FORCEPROP 1 LAST OFFPAGE TRUE
J 0
(-12125 1850);
DISPLAY 0.872340 (-12125 1850);
PAINT GREEN (-12125 1850);
DISPLAY INVISIBLE (-12125 1850);
FORCEPROP 1 LAST COMMENT_BODY TRUE
J 0
(-12350 1900);
DISPLAY 0.872340 (-12350 1900);
PAINT PEACH (-12350 1900);
DISPLAY INVISIBLE (-12350 1900);
FORCEPROP 2 LAST CDS_LIB standard
J 0
(-12450 1975);
DISPLAY INVISIBLE (-12450 1975);
FORCEPROP 2 LAST PATH I125
J 0
(-12750 2025);
DISPLAY 1.021277 (-12750 2025);
DISPLAY INVISIBLE (-12750 2025);
FORCEADD UNIVERSAL_POWER..1
(-11275 2450);
FORCEPROP 3 LASTPIN (-11275 2400) SIG_NAME P12V_SCM\g
J 0
(-11265 2410);
DISPLAY 0.659574 (-11265 2410);
PAINT MONO (-11265 2410);
DISPLAY INVISIBLE (-11265 2410);
FORCEPROP 1 LAST HDL_POWER P12V_SCM
J 1
(-11275 2500);
DISPLAY 0.702128 (-11275 2500);
PAINT GREEN (-11275 2500);
FORCEPROP 2 LAST CDS_LIB logical_power
J 0
(-11275 2450);
DISPLAY INVISIBLE (-11275 2450);
FORCEPROP 1 LAST PATH I126
J 0
(-11225 2475);
DISPLAY 0.872340 (-11225 2475);
PAINT AQUA (-11225 2475);
DISPLAY INVISIBLE (-11225 2475);
FORCEADD OFFPAGE..4
(-8350 -475);
FORCEPROP 2 LAST $XR0 222 
J 0
(-8164 -475);
DISPLAY 0.638298 (-8164 -475);
PAINT MONO (-8164 -475);
FORCEPROP 1 LAST OFFPAGE TRUE
J 0
(-8025 -600);
DISPLAY 0.872340 (-8025 -600);
PAINT GREEN (-8025 -600);
DISPLAY INVISIBLE (-8025 -600);
FORCEPROP 1 LAST COMMENT_BODY TRUE
J 0
(-8375 -575);
DISPLAY 0.872340 (-8375 -575);
PAINT PEACH (-8375 -575);
DISPLAY INVISIBLE (-8375 -575);
FORCEPROP 2 LAST CDS_LIB standard
J 0
(-8350 -475);
PAINT MONO (-8350 -475);
DISPLAY INVISIBLE (-8350 -475);
FORCEPROP 2 LAST PATH I127
J 0
(-8150 -425);
DISPLAY 1.021277 (-8150 -425);
DISPLAY INVISIBLE (-8150 -425);
FORCEADD OFFPAGE..2
(-8350 -425);
FORCEPROP 2 LAST $XR0 222 
J 0
(-8161 -425);
DISPLAY 0.638298 (-8161 -425);
PAINT MONO (-8161 -425);
FORCEPROP 1 LAST COMMENT_BODY TRUE
J 0
(-8395 -520);
DISPLAY 0.872340 (-8395 -520);
PAINT PEACH (-8395 -520);
DISPLAY INVISIBLE (-8395 -520);
FORCEPROP 1 LAST OFFPAGE TRUE
J 0
(-8025 -550);
DISPLAY 0.872340 (-8025 -550);
PAINT GREEN (-8025 -550);
DISPLAY INVISIBLE (-8025 -550);
FORCEPROP 2 LAST CDS_LIB standard
J 0
(-8350 -425);
DISPLAY INVISIBLE (-8350 -425);
FORCEPROP 2 LAST PATH I128
J 0
(-8150 -375);
DISPLAY 1.021277 (-8150 -375);
DISPLAY INVISIBLE (-8150 -375);
FORCEADD OFFPAGE..2
(-8350 -375);
FORCEPROP 2 LAST $XR0 222 
J 0
(-8161 -375);
DISPLAY 0.638298 (-8161 -375);
PAINT MONO (-8161 -375);
FORCEPROP 2 LAST CDS_LIB standard
J 0
(-8350 -375);
PAINT MONO (-8350 -375);
DISPLAY INVISIBLE (-8350 -375);
FORCEPROP 1 LAST OFFPAGE TRUE
J 0
(-8025 -500);
DISPLAY 0.872340 (-8025 -500);
PAINT GREEN (-8025 -500);
DISPLAY INVISIBLE (-8025 -500);
FORCEPROP 1 LAST COMMENT_BODY TRUE
J 0
(-8395 -470);
DISPLAY 0.872340 (-8395 -470);
PAINT PEACH (-8395 -470);
DISPLAY INVISIBLE (-8395 -470);
FORCEPROP 2 LAST PATH I129
J 0
(-8150 -325);
DISPLAY 1.021277 (-8150 -325);
DISPLAY INVISIBLE (-8150 -325);
FORCEADD OFFPAGE..6
(-14575 -625);
FORCEPROP 2 LAST $XR0 241 
J 0
(-14855 -625);
DISPLAY 0.638298 (-14855 -625);
PAINT MONO (-14855 -625);
FORCEPROP 2 LAST $XR1 234 
J 0
(-14975 -625);
DISPLAY 0.638298 (-14975 -625);
PAINT MONO (-14975 -625);
FORCEPROP 2 LAST CDS_LIB standard
J 0
(-14575 -625);
DISPLAY INVISIBLE (-14575 -625);
FORCEPROP 1 LAST OFFPAGE TRUE
J 0
(-14250 -750);
DISPLAY 0.872340 (-14250 -750);
PAINT GREEN (-14250 -750);
DISPLAY INVISIBLE (-14250 -750);
FORCEPROP 1 LAST COMMENT_BODY TRUE
J 0
(-14475 -700);
DISPLAY 0.872340 (-14475 -700);
PAINT PEACH (-14475 -700);
DISPLAY INVISIBLE (-14475 -700);
FORCEPROP 2 LAST PATH I13
J 0
(-14850 -575);
DISPLAY 1.021277 (-14850 -575);
DISPLAY INVISIBLE (-14850 -575);
FORCEADD OFFPAGE..2
(-8350 -275);
FORCEPROP 2 LAST $XR0 222 
J 0
(-8161 -275);
DISPLAY 0.638298 (-8161 -275);
PAINT MONO (-8161 -275);
FORCEPROP 2 LAST CDS_LIB standard
J 0
(-8350 -275);
PAINT MONO (-8350 -275);
DISPLAY INVISIBLE (-8350 -275);
FORCEPROP 1 LAST OFFPAGE TRUE
J 0
(-8025 -400);
DISPLAY 0.872340 (-8025 -400);
PAINT GREEN (-8025 -400);
DISPLAY INVISIBLE (-8025 -400);
FORCEPROP 1 LAST COMMENT_BODY TRUE
J 0
(-8395 -370);
DISPLAY 0.872340 (-8395 -370);
PAINT PEACH (-8395 -370);
DISPLAY INVISIBLE (-8395 -370);
FORCEPROP 2 LAST PATH I130
J 0
(-8150 -225);
DISPLAY 1.021277 (-8150 -225);
DISPLAY INVISIBLE (-8150 -225);
FORCEADD OFFPAGE..4
(-8350 -225);
FORCEPROP 2 LAST $XR0 222 
J 0
(-8164 -225);
DISPLAY 0.638298 (-8164 -225);
PAINT MONO (-8164 -225);
FORCEPROP 1 LAST COMMENT_BODY TRUE
J 0
(-8375 -325);
DISPLAY 0.872340 (-8375 -325);
PAINT PEACH (-8375 -325);
DISPLAY INVISIBLE (-8375 -325);
FORCEPROP 1 LAST OFFPAGE TRUE
J 0
(-8025 -350);
DISPLAY 0.872340 (-8025 -350);
PAINT GREEN (-8025 -350);
DISPLAY INVISIBLE (-8025 -350);
FORCEPROP 2 LAST CDS_LIB standard
J 0
(-8350 -225);
PAINT MONO (-8350 -225);
DISPLAY INVISIBLE (-8350 -225);
FORCEPROP 2 LAST PATH I131
J 0
(-8150 -175);
DISPLAY 1.021277 (-8150 -175);
DISPLAY INVISIBLE (-8150 -175);
FORCEADD OFFPAGE..2
(-8350 -175);
FORCEPROP 2 LAST $XR0 222 
J 0
(-8161 -175);
DISPLAY 0.638298 (-8161 -175);
PAINT MONO (-8161 -175);
FORCEPROP 2 LAST CDS_LIB standard
J 0
(-8350 -175);
PAINT MONO (-8350 -175);
DISPLAY INVISIBLE (-8350 -175);
FORCEPROP 1 LAST OFFPAGE TRUE
J 0
(-8025 -300);
DISPLAY 0.872340 (-8025 -300);
PAINT GREEN (-8025 -300);
DISPLAY INVISIBLE (-8025 -300);
FORCEPROP 1 LAST COMMENT_BODY TRUE
J 0
(-8395 -270);
DISPLAY 0.872340 (-8395 -270);
PAINT PEACH (-8395 -270);
DISPLAY INVISIBLE (-8395 -270);
FORCEPROP 2 LAST PATH I132
J 0
(-8150 -125);
DISPLAY 1.021277 (-8150 -125);
DISPLAY INVISIBLE (-8150 -125);
FORCEADD OFFPAGE..2
(-8350 -125);
FORCEPROP 2 LAST $XR0 222 
J 0
(-8161 -125);
DISPLAY 0.638298 (-8161 -125);
PAINT MONO (-8161 -125);
FORCEPROP 1 LAST OFFPAGE TRUE
J 0
(-8025 -250);
DISPLAY 0.872340 (-8025 -250);
PAINT GREEN (-8025 -250);
DISPLAY INVISIBLE (-8025 -250);
FORCEPROP 1 LAST COMMENT_BODY TRUE
J 0
(-8395 -220);
DISPLAY 0.872340 (-8395 -220);
PAINT PEACH (-8395 -220);
DISPLAY INVISIBLE (-8395 -220);
FORCEPROP 2 LAST CDS_LIB standard
J 0
(-8350 -125);
PAINT MONO (-8350 -125);
DISPLAY INVISIBLE (-8350 -125);
FORCEPROP 2 LAST PATH I133
J 0
(-8150 -75);
DISPLAY 1.021277 (-8150 -75);
DISPLAY INVISIBLE (-8150 -75);
FORCEADD OFFPAGE..3
(-8350 75);
FORCEPROP 2 LAST $XR0 197 
J 0
(-8136 75);
DISPLAY 0.638298 (-8136 75);
PAINT MONO (-8136 75);
FORCEPROP 2 LAST CDS_LIB standard
J 0
(-8350 75);
DISPLAY INVISIBLE (-8350 75);
FORCEPROP 1 LAST COMMENT_BODY TRUE
J 0
(-8400 -25);
DISPLAY 0.872340 (-8400 -25);
PAINT PEACH (-8400 -25);
DISPLAY INVISIBLE (-8400 -25);
FORCEPROP 1 LAST OFFPAGE TRUE
J 0
(-8025 -50);
DISPLAY 0.872340 (-8025 -50);
PAINT GREEN (-8025 -50);
DISPLAY INVISIBLE (-8025 -50);
FORCEPROP 2 LAST PATH I134
J 0
(-8125 125);
DISPLAY 1.021277 (-8125 125);
DISPLAY INVISIBLE (-8125 125);
FORCEADD OFFPAGE..2
(-8350 25);
FORCEPROP 2 LAST $XR0 240 
J 0
(-8131 25);
DISPLAY 0.638298 (-8131 25);
PAINT MONO (-8131 25);
FORCEPROP 2 LAST CDS_LIB standard
J 0
(-8350 25);
DISPLAY INVISIBLE (-8350 25);
FORCEPROP 1 LAST COMMENT_BODY TRUE
J 0
(-8395 -70);
DISPLAY 0.872340 (-8395 -70);
PAINT PEACH (-8395 -70);
DISPLAY INVISIBLE (-8395 -70);
FORCEPROP 1 LAST OFFPAGE TRUE
J 0
(-8025 -100);
DISPLAY 0.872340 (-8025 -100);
PAINT GREEN (-8025 -100);
DISPLAY INVISIBLE (-8025 -100);
FORCEPROP 2 LAST PATH I135
J 0
(-8125 75);
DISPLAY 1.021277 (-8125 75);
DISPLAY INVISIBLE (-8125 75);
FORCEADD OFFPAGE..4
(-8350 175);
FORCEPROP 2 LAST $XR1 160 
J 0
(-8044 175);
DISPLAY 0.638298 (-8044 175);
PAINT MONO (-8044 175);
FORCEPROP 2 LAST $XR0 154 
J 0
(-8164 175);
DISPLAY 0.638298 (-8164 175);
PAINT MONO (-8164 175);
FORCEPROP 2 LAST CDS_LIB standard
J 0
(-8350 175);
PAINT MONO (-8350 175);
DISPLAY INVISIBLE (-8350 175);
FORCEPROP 1 LAST COMMENT_BODY TRUE
J 0
(-8375 75);
DISPLAY 0.872340 (-8375 75);
PAINT PEACH (-8375 75);
DISPLAY INVISIBLE (-8375 75);
FORCEPROP 1 LAST OFFPAGE TRUE
J 0
(-8025 50);
DISPLAY 0.872340 (-8025 50);
PAINT GREEN (-8025 50);
DISPLAY INVISIBLE (-8025 50);
FORCEPROP 2 LAST PATH I136
J 0
(-8025 225);
DISPLAY 1.021277 (-8025 225);
DISPLAY INVISIBLE (-8025 225);
FORCEADD OFFPAGE..4
(-8350 225);
FORCEPROP 2 LAST $XR1 160 
J 0
(-8044 225);
DISPLAY 0.638298 (-8044 225);
PAINT MONO (-8044 225);
FORCEPROP 2 LAST $XR0 154 
J 0
(-8164 225);
DISPLAY 0.638298 (-8164 225);
PAINT MONO (-8164 225);
FORCEPROP 2 LAST CDS_LIB standard
J 0
(-8350 225);
PAINT MONO (-8350 225);
DISPLAY INVISIBLE (-8350 225);
FORCEPROP 1 LAST OFFPAGE TRUE
J 0
(-8025 100);
DISPLAY 0.872340 (-8025 100);
PAINT GREEN (-8025 100);
DISPLAY INVISIBLE (-8025 100);
FORCEPROP 1 LAST COMMENT_BODY TRUE
J 0
(-8375 125);
DISPLAY 0.872340 (-8375 125);
PAINT PEACH (-8375 125);
DISPLAY INVISIBLE (-8375 125);
FORCEPROP 2 LAST PATH I137
J 0
(-8025 275);
DISPLAY 1.021277 (-8025 275);
DISPLAY INVISIBLE (-8025 275);
FORCEADD OFFPAGE..2
(-8350 325);
FORCEPROP 2 LAST $XR1 160 
J 0
(-8041 325);
DISPLAY 0.638298 (-8041 325);
PAINT MONO (-8041 325);
FORCEPROP 2 LAST $XR0 154 
J 0
(-8161 325);
DISPLAY 0.638298 (-8161 325);
PAINT MONO (-8161 325);
FORCEPROP 1 LAST OFFPAGE TRUE
J 0
(-8025 200);
DISPLAY 0.872340 (-8025 200);
PAINT GREEN (-8025 200);
DISPLAY INVISIBLE (-8025 200);
FORCEPROP 1 LAST COMMENT_BODY TRUE
J 0
(-8395 230);
DISPLAY 0.872340 (-8395 230);
PAINT PEACH (-8395 230);
DISPLAY INVISIBLE (-8395 230);
FORCEPROP 2 LAST CDS_LIB standard
J 0
(-8350 325);
PAINT MONO (-8350 325);
DISPLAY INVISIBLE (-8350 325);
FORCEPROP 2 LAST PATH I138
J 0
(-8025 375);
DISPLAY 1.021277 (-8025 375);
DISPLAY INVISIBLE (-8025 375);
FORCEADD OFFPAGE..2
(-8350 275);
FORCEPROP 2 LAST $XR0 154 
J 0
(-8161 275);
DISPLAY 0.638298 (-8161 275);
PAINT MONO (-8161 275);
FORCEPROP 2 LAST CDS_LIB standard
J 0
(-8350 275);
PAINT MONO (-8350 275);
DISPLAY INVISIBLE (-8350 275);
FORCEPROP 1 LAST OFFPAGE TRUE
J 0
(-8025 150);
DISPLAY 0.872340 (-8025 150);
PAINT GREEN (-8025 150);
DISPLAY INVISIBLE (-8025 150);
FORCEPROP 1 LAST COMMENT_BODY TRUE
J 0
(-8395 180);
DISPLAY 0.872340 (-8395 180);
PAINT PEACH (-8395 180);
DISPLAY INVISIBLE (-8395 180);
FORCEPROP 2 LAST PATH I139
J 0
(-8150 325);
DISPLAY 1.021277 (-8150 325);
DISPLAY INVISIBLE (-8150 325);
FORCEADD OFFPAGE..6
(-14575 -675);
FORCEPROP 2 LAST $XR0 241 
J 0
(-14855 -675);
DISPLAY 0.638298 (-14855 -675);
PAINT MONO (-14855 -675);
FORCEPROP 2 LAST $XR1 236 
J 0
(-14975 -675);
DISPLAY 0.638298 (-14975 -675);
PAINT MONO (-14975 -675);
FORCEPROP 2 LAST CDS_LIB standard
J 0
(-14575 -675);
DISPLAY INVISIBLE (-14575 -675);
FORCEPROP 1 LAST OFFPAGE TRUE
J 0
(-14250 -800);
DISPLAY 0.872340 (-14250 -800);
PAINT GREEN (-14250 -800);
DISPLAY INVISIBLE (-14250 -800);
FORCEPROP 1 LAST COMMENT_BODY TRUE
J 0
(-14475 -750);
DISPLAY 0.872340 (-14475 -750);
PAINT PEACH (-14475 -750);
DISPLAY INVISIBLE (-14475 -750);
FORCEPROP 2 LAST PATH I14
J 0
(-14850 -625);
DISPLAY 1.021277 (-14850 -625);
DISPLAY INVISIBLE (-14850 -625);
FORCEADD OFFPAGE..2
(-8350 375);
FORCEPROP 2 LAST $XR1 160 
J 0
(-8041 375);
DISPLAY 0.638298 (-8041 375);
PAINT MONO (-8041 375);
FORCEPROP 2 LAST $XR0 154 
J 0
(-8161 375);
DISPLAY 0.638298 (-8161 375);
PAINT MONO (-8161 375);
FORCEPROP 1 LAST OFFPAGE TRUE
J 0
(-8025 250);
DISPLAY 0.872340 (-8025 250);
PAINT GREEN (-8025 250);
DISPLAY INVISIBLE (-8025 250);
FORCEPROP 1 LAST COMMENT_BODY TRUE
J 0
(-8395 280);
DISPLAY 0.872340 (-8395 280);
PAINT PEACH (-8395 280);
DISPLAY INVISIBLE (-8395 280);
FORCEPROP 2 LAST CDS_LIB standard
J 0
(-8350 375);
PAINT MONO (-8350 375);
DISPLAY INVISIBLE (-8350 375);
FORCEPROP 2 LAST PATH I140
J 0
(-8025 425);
DISPLAY 1.021277 (-8025 425);
DISPLAY INVISIBLE (-8025 425);
FORCEADD OFFPAGE..2
(-8350 425);
FORCEPROP 2 LAST $XR0 154 
J 0
(-8161 425);
DISPLAY 0.638298 (-8161 425);
PAINT MONO (-8161 425);
FORCEPROP 2 LAST $XR1 160 
J 0
(-8041 425);
DISPLAY 0.638298 (-8041 425);
PAINT MONO (-8041 425);
FORCEPROP 2 LAST CDS_LIB standard
J 0
(-8350 425);
DISPLAY INVISIBLE (-8350 425);
FORCEPROP 1 LAST COMMENT_BODY TRUE
J 0
(-8395 330);
DISPLAY 0.872340 (-8395 330);
PAINT PEACH (-8395 330);
DISPLAY INVISIBLE (-8395 330);
FORCEPROP 1 LAST OFFPAGE TRUE
J 0
(-8025 300);
DISPLAY 0.872340 (-8025 300);
PAINT GREEN (-8025 300);
DISPLAY INVISIBLE (-8025 300);
FORCEPROP 2 LAST PATH I141
J 0
(-8025 475);
DISPLAY 1.021277 (-8025 475);
DISPLAY INVISIBLE (-8025 475);
FORCEADD OFFPAGE..4
(-8350 475);
FORCEPROP 2 LAST $XR0 154 
J 0
(-8164 475);
DISPLAY 0.638298 (-8164 475);
PAINT MONO (-8164 475);
FORCEPROP 2 LAST $XR1 160 
J 0
(-8044 475);
DISPLAY 0.638298 (-8044 475);
PAINT MONO (-8044 475);
FORCEPROP 2 LAST CDS_LIB standard
J 0
(-8350 475);
DISPLAY INVISIBLE (-8350 475);
FORCEPROP 1 LAST OFFPAGE TRUE
J 0
(-8025 350);
DISPLAY 0.872340 (-8025 350);
PAINT GREEN (-8025 350);
DISPLAY INVISIBLE (-8025 350);
FORCEPROP 1 LAST COMMENT_BODY TRUE
J 0
(-8375 375);
DISPLAY 0.872340 (-8375 375);
PAINT PEACH (-8375 375);
DISPLAY INVISIBLE (-8375 375);
FORCEPROP 2 LAST PATH I142
J 0
(-8025 525);
DISPLAY 1.021277 (-8025 525);
DISPLAY INVISIBLE (-8025 525);
FORCEADD OFFPAGE..4
(-8350 525);
FORCEPROP 2 LAST $XR0 155 
J 0
(-8164 525);
DISPLAY 0.638298 (-8164 525);
PAINT MONO (-8164 525);
FORCEPROP 1 LAST COMMENT_BODY TRUE
J 0
(-8375 425);
DISPLAY 0.872340 (-8375 425);
PAINT PEACH (-8375 425);
DISPLAY INVISIBLE (-8375 425);
FORCEPROP 1 LAST OFFPAGE TRUE
J 0
(-8025 400);
DISPLAY 0.872340 (-8025 400);
PAINT GREEN (-8025 400);
DISPLAY INVISIBLE (-8025 400);
FORCEPROP 2 LAST CDS_LIB standard
J 0
(-8350 525);
PAINT MONO (-8350 525);
DISPLAY INVISIBLE (-8350 525);
FORCEPROP 2 LAST PATH I143
J 0
(-8150 575);
DISPLAY 1.021277 (-8150 575);
DISPLAY INVISIBLE (-8150 575);
FORCEADD OFFPAGE..4
(-8350 625);
FORCEPROP 2 LAST $XR0 185 
J 0
(-8164 625);
DISPLAY 0.638298 (-8164 625);
PAINT MONO (-8164 625);
FORCEPROP 1 LAST OFFPAGE TRUE
J 0
(-8025 500);
DISPLAY 0.872340 (-8025 500);
PAINT GREEN (-8025 500);
DISPLAY INVISIBLE (-8025 500);
FORCEPROP 1 LAST COMMENT_BODY TRUE
J 0
(-8375 525);
DISPLAY 0.872340 (-8375 525);
PAINT PEACH (-8375 525);
DISPLAY INVISIBLE (-8375 525);
FORCEPROP 2 LAST CDS_LIB standard
J 0
(-8350 625);
PAINT MONO (-8350 625);
DISPLAY INVISIBLE (-8350 625);
FORCEPROP 2 LAST PATH I144
J 0
(-8150 675);
DISPLAY 1.021277 (-8150 675);
DISPLAY INVISIBLE (-8150 675);
FORCEADD OFFPAGE..4
(-8350 725);
FORCEPROP 2 LAST $XR0 185 
J 0
(-8164 725);
DISPLAY 0.638298 (-8164 725);
PAINT MONO (-8164 725);
FORCEPROP 2 LAST CDS_LIB standard
J 0
(-8350 725);
PAINT MONO (-8350 725);
DISPLAY INVISIBLE (-8350 725);
FORCEPROP 1 LAST COMMENT_BODY TRUE
J 0
(-8375 625);
DISPLAY 0.872340 (-8375 625);
PAINT PEACH (-8375 625);
DISPLAY INVISIBLE (-8375 625);
FORCEPROP 1 LAST OFFPAGE TRUE
J 0
(-8025 600);
DISPLAY 0.872340 (-8025 600);
PAINT GREEN (-8025 600);
DISPLAY INVISIBLE (-8025 600);
FORCEPROP 2 LAST PATH I145
J 0
(-8150 775);
DISPLAY 1.021277 (-8150 775);
DISPLAY INVISIBLE (-8150 775);
FORCEADD OFFPAGE..4
(-8350 675);
FORCEPROP 2 LAST $XR0 185 
J 0
(-8164 675);
DISPLAY 0.638298 (-8164 675);
PAINT MONO (-8164 675);
FORCEPROP 2 LAST CDS_LIB standard
J 0
(-8350 675);
PAINT MONO (-8350 675);
DISPLAY INVISIBLE (-8350 675);
FORCEPROP 1 LAST COMMENT_BODY TRUE
J 0
(-8375 575);
DISPLAY 0.872340 (-8375 575);
PAINT PEACH (-8375 575);
DISPLAY INVISIBLE (-8375 575);
FORCEPROP 1 LAST OFFPAGE TRUE
J 0
(-8025 550);
DISPLAY 0.872340 (-8025 550);
PAINT GREEN (-8025 550);
DISPLAY INVISIBLE (-8025 550);
FORCEPROP 2 LAST PATH I146
J 0
(-8150 725);
DISPLAY 1.021277 (-8150 725);
DISPLAY INVISIBLE (-8150 725);
FORCEADD OFFPAGE..4
(-8350 775);
FORCEPROP 2 LAST $XR0 185 
J 0
(-8164 775);
DISPLAY 0.638298 (-8164 775);
PAINT MONO (-8164 775);
FORCEPROP 2 LAST CDS_LIB standard
J 0
(-8350 775);
PAINT MONO (-8350 775);
DISPLAY INVISIBLE (-8350 775);
FORCEPROP 1 LAST COMMENT_BODY TRUE
J 0
(-8375 675);
DISPLAY 0.872340 (-8375 675);
PAINT PEACH (-8375 675);
DISPLAY INVISIBLE (-8375 675);
FORCEPROP 1 LAST OFFPAGE TRUE
J 0
(-8025 650);
DISPLAY 0.872340 (-8025 650);
PAINT GREEN (-8025 650);
DISPLAY INVISIBLE (-8025 650);
FORCEPROP 2 LAST PATH I147
J 0
(-8150 825);
DISPLAY 1.021277 (-8150 825);
DISPLAY INVISIBLE (-8150 825);
FORCEADD OFFPAGE..4
(-8350 875);
FORCEPROP 2 LAST $XR0 185 
J 0
(-8164 875);
DISPLAY 0.638298 (-8164 875);
PAINT MONO (-8164 875);
FORCEPROP 2 LAST CDS_LIB standard
J 0
(-8350 875);
PAINT MONO (-8350 875);
DISPLAY INVISIBLE (-8350 875);
FORCEPROP 1 LAST OFFPAGE TRUE
J 0
(-8025 750);
DISPLAY 0.872340 (-8025 750);
PAINT GREEN (-8025 750);
DISPLAY INVISIBLE (-8025 750);
FORCEPROP 1 LAST COMMENT_BODY TRUE
J 0
(-8375 775);
DISPLAY 0.872340 (-8375 775);
PAINT PEACH (-8375 775);
DISPLAY INVISIBLE (-8375 775);
FORCEPROP 2 LAST PATH I148
J 0
(-8150 925);
DISPLAY 1.021277 (-8150 925);
DISPLAY INVISIBLE (-8150 925);
FORCEADD OFFPAGE..4
(-8350 825);
FORCEPROP 2 LAST $XR0 185 
J 0
(-8164 825);
DISPLAY 0.638298 (-8164 825);
PAINT MONO (-8164 825);
FORCEPROP 2 LAST CDS_LIB standard
J 0
(-8350 825);
PAINT MONO (-8350 825);
DISPLAY INVISIBLE (-8350 825);
FORCEPROP 1 LAST OFFPAGE TRUE
J 0
(-8025 700);
DISPLAY 0.872340 (-8025 700);
PAINT GREEN (-8025 700);
DISPLAY INVISIBLE (-8025 700);
FORCEPROP 1 LAST COMMENT_BODY TRUE
J 0
(-8375 725);
DISPLAY 0.872340 (-8375 725);
PAINT PEACH (-8375 725);
DISPLAY INVISIBLE (-8375 725);
FORCEPROP 2 LAST PATH I149
J 0
(-8150 875);
DISPLAY 1.021277 (-8150 875);
DISPLAY INVISIBLE (-8150 875);
FORCEADD OFFPAGE..6
(-14575 -725);
FORCEPROP 2 LAST $XR0 236 
J 0
(-14855 -725);
DISPLAY 0.638298 (-14855 -725);
PAINT MONO (-14855 -725);
FORCEPROP 2 LAST $XR1 241 
J 0
(-14975 -725);
DISPLAY 0.638298 (-14975 -725);
PAINT MONO (-14975 -725);
FORCEPROP 2 LAST CDS_LIB standard
J 0
(-14575 -725);
DISPLAY INVISIBLE (-14575 -725);
FORCEPROP 1 LAST COMMENT_BODY TRUE
J 0
(-14475 -800);
DISPLAY 0.872340 (-14475 -800);
PAINT PEACH (-14475 -800);
DISPLAY INVISIBLE (-14475 -800);
FORCEPROP 1 LAST OFFPAGE TRUE
J 0
(-14250 -850);
DISPLAY 0.872340 (-14250 -850);
PAINT GREEN (-14250 -850);
DISPLAY INVISIBLE (-14250 -850);
FORCEPROP 2 LAST PATH I15
J 0
(-14850 -675);
DISPLAY 1.021277 (-14850 -675);
DISPLAY INVISIBLE (-14850 -675);
FORCEADD OFFPAGE..4
(-8350 975);
FORCEPROP 2 LAST $XR0 257 
J 0
(-8134 975);
DISPLAY 0.638298 (-8134 975);
PAINT MONO (-8134 975);
FORCEPROP 1 LAST COMMENT_BODY TRUE
J 0
(-8375 875);
DISPLAY 0.872340 (-8375 875);
PAINT PEACH (-8375 875);
DISPLAY INVISIBLE (-8375 875);
FORCEPROP 1 LAST OFFPAGE TRUE
J 0
(-8025 850);
DISPLAY 0.872340 (-8025 850);
PAINT GREEN (-8025 850);
DISPLAY INVISIBLE (-8025 850);
FORCEPROP 2 LAST CDS_LIB standard
J 0
(-8350 975);
PAINT MONO (-8350 975);
DISPLAY INVISIBLE (-8350 975);
FORCEPROP 2 LAST PATH I150
J 0
(-8125 1025);
DISPLAY 1.021277 (-8125 1025);
DISPLAY INVISIBLE (-8125 1025);
FORCEADD OFFPAGE..3
(-8350 1025);
FORCEPROP 2 LAST $XR0 202 
J 0
(-8136 1025);
DISPLAY 0.638298 (-8136 1025);
PAINT MONO (-8136 1025);
FORCEPROP 1 LAST COMMENT_BODY TRUE
J 0
(-8400 925);
DISPLAY 0.872340 (-8400 925);
PAINT PEACH (-8400 925);
DISPLAY INVISIBLE (-8400 925);
FORCEPROP 2 LAST CDS_LIB standard
J 0
(-8350 1025);
DISPLAY INVISIBLE (-8350 1025);
FORCEPROP 1 LAST OFFPAGE TRUE
J 0
(-8025 900);
DISPLAY 0.872340 (-8025 900);
PAINT GREEN (-8025 900);
DISPLAY INVISIBLE (-8025 900);
FORCEPROP 2 LAST PATH I151
J 0
(-8125 1075);
DISPLAY 1.021277 (-8125 1075);
DISPLAY INVISIBLE (-8125 1075);
FORCEADD OFFPAGE..3
(-8350 1075);
FORCEPROP 2 LAST $XR0 202 
J 0
(-8136 1075);
DISPLAY 0.638298 (-8136 1075);
PAINT MONO (-8136 1075);
FORCEPROP 1 LAST COMMENT_BODY TRUE
J 0
(-8400 975);
DISPLAY 0.872340 (-8400 975);
PAINT PEACH (-8400 975);
DISPLAY INVISIBLE (-8400 975);
FORCEPROP 2 LAST CDS_LIB standard
J 0
(-8350 1075);
DISPLAY INVISIBLE (-8350 1075);
FORCEPROP 1 LAST OFFPAGE TRUE
J 0
(-8025 950);
DISPLAY 0.872340 (-8025 950);
PAINT GREEN (-8025 950);
DISPLAY INVISIBLE (-8025 950);
FORCEPROP 2 LAST PATH I152
J 0
(-8125 1125);
DISPLAY 1.021277 (-8125 1125);
DISPLAY INVISIBLE (-8125 1125);
FORCEADD OFFPAGE..3
(-8350 1125);
FORCEPROP 2 LAST $XR0 202 
J 0
(-8136 1125);
DISPLAY 0.638298 (-8136 1125);
PAINT MONO (-8136 1125);
FORCEPROP 1 LAST COMMENT_BODY TRUE
J 0
(-8400 1025);
DISPLAY 0.872340 (-8400 1025);
PAINT PEACH (-8400 1025);
DISPLAY INVISIBLE (-8400 1025);
FORCEPROP 2 LAST CDS_LIB standard
J 0
(-8350 1125);
DISPLAY INVISIBLE (-8350 1125);
FORCEPROP 1 LAST OFFPAGE TRUE
J 0
(-8025 1000);
DISPLAY 0.872340 (-8025 1000);
PAINT GREEN (-8025 1000);
DISPLAY INVISIBLE (-8025 1000);
FORCEPROP 2 LAST PATH I153
J 0
(-8125 1175);
DISPLAY 1.021277 (-8125 1175);
DISPLAY INVISIBLE (-8125 1175);
FORCEADD OFFPAGE..3
(-8350 1175);
FORCEPROP 2 LAST $XR0 202 
J 0
(-8136 1175);
DISPLAY 0.638298 (-8136 1175);
PAINT MONO (-8136 1175);
FORCEPROP 1 LAST OFFPAGE TRUE
J 0
(-8025 1050);
DISPLAY 0.872340 (-8025 1050);
PAINT GREEN (-8025 1050);
DISPLAY INVISIBLE (-8025 1050);
FORCEPROP 1 LAST COMMENT_BODY TRUE
J 0
(-8400 1075);
DISPLAY 0.872340 (-8400 1075);
PAINT PEACH (-8400 1075);
DISPLAY INVISIBLE (-8400 1075);
FORCEPROP 2 LAST CDS_LIB standard
J 0
(-8350 1175);
DISPLAY INVISIBLE (-8350 1175);
FORCEPROP 2 LAST PATH I154
J 0
(-8125 1225);
DISPLAY 1.021277 (-8125 1225);
DISPLAY INVISIBLE (-8125 1225);
FORCEADD OFFPAGE..4
(-8350 1225);
FORCEPROP 2 LAST $XR0 202 
J 0
(-8134 1225);
DISPLAY 0.638298 (-8134 1225);
PAINT MONO (-8134 1225);
FORCEPROP 2 LAST CDS_LIB standard
J 0
(-8350 1225);
PAINT MONO (-8350 1225);
DISPLAY INVISIBLE (-8350 1225);
FORCEPROP 1 LAST COMMENT_BODY TRUE
J 0
(-8375 1125);
DISPLAY 0.872340 (-8375 1125);
PAINT PEACH (-8375 1125);
DISPLAY INVISIBLE (-8375 1125);
FORCEPROP 1 LAST OFFPAGE TRUE
J 0
(-8025 1100);
DISPLAY 0.872340 (-8025 1100);
PAINT GREEN (-8025 1100);
DISPLAY INVISIBLE (-8025 1100);
FORCEPROP 2 LAST PATH I155
J 0
(-8125 1275);
DISPLAY 1.021277 (-8125 1275);
DISPLAY INVISIBLE (-8125 1275);
FORCEADD OFFPAGE..3
(-8350 1275);
FORCEPROP 2 LAST $XR0 202 
J 0
(-8136 1275);
DISPLAY 0.638298 (-8136 1275);
PAINT MONO (-8136 1275);
FORCEPROP 1 LAST OFFPAGE TRUE
J 0
(-8025 1150);
DISPLAY 0.872340 (-8025 1150);
PAINT GREEN (-8025 1150);
DISPLAY INVISIBLE (-8025 1150);
FORCEPROP 2 LAST CDS_LIB standard
J 0
(-8350 1275);
DISPLAY INVISIBLE (-8350 1275);
FORCEPROP 1 LAST COMMENT_BODY TRUE
J 0
(-8400 1175);
DISPLAY 0.872340 (-8400 1175);
PAINT PEACH (-8400 1175);
DISPLAY INVISIBLE (-8400 1175);
FORCEPROP 2 LAST PATH I156
J 0
(-8125 1325);
DISPLAY 1.021277 (-8125 1325);
DISPLAY INVISIBLE (-8125 1325);
FORCEADD OFFPAGE..4
(-8350 1375);
FORCEPROP 2 LAST $XR0 202 
J 0
(-8164 1375);
DISPLAY 0.638298 (-8164 1375);
PAINT MONO (-8164 1375);
FORCEPROP 1 LAST OFFPAGE TRUE
J 0
(-8025 1250);
DISPLAY 0.872340 (-8025 1250);
PAINT GREEN (-8025 1250);
DISPLAY INVISIBLE (-8025 1250);
FORCEPROP 1 LAST COMMENT_BODY TRUE
J 0
(-8375 1275);
DISPLAY 0.872340 (-8375 1275);
PAINT PEACH (-8375 1275);
DISPLAY INVISIBLE (-8375 1275);
FORCEPROP 2 LAST CDS_LIB standard
J 0
(-8350 1375);
DISPLAY INVISIBLE (-8350 1375);
FORCEPROP 2 LAST PATH I157
J 0
(-8150 1425);
DISPLAY 1.021277 (-8150 1425);
DISPLAY INVISIBLE (-8150 1425);
FORCEADD OFFPAGE..2
(-8350 1325);
FORCEPROP 2 LAST $XR0 202 
J 0
(-8161 1325);
DISPLAY 0.638298 (-8161 1325);
PAINT MONO (-8161 1325);
FORCEPROP 2 LAST CDS_LIB standard
J 0
(-8350 1325);
PAINT MONO (-8350 1325);
DISPLAY INVISIBLE (-8350 1325);
FORCEPROP 1 LAST OFFPAGE TRUE
J 0
(-8025 1200);
DISPLAY 0.872340 (-8025 1200);
PAINT GREEN (-8025 1200);
DISPLAY INVISIBLE (-8025 1200);
FORCEPROP 1 LAST COMMENT_BODY TRUE
J 0
(-8395 1230);
DISPLAY 0.872340 (-8395 1230);
PAINT PEACH (-8395 1230);
DISPLAY INVISIBLE (-8395 1230);
FORCEPROP 2 LAST PATH I158
J 0
(-8150 1375);
DISPLAY 1.021277 (-8150 1375);
DISPLAY INVISIBLE (-8150 1375);
FORCEADD Q_RES..1
(-7800 1525);
FORCEPROP 1 LAST PART_NUMBER CS00002JB13
J 0
(-7925 1600);
DISPLAY 0.638298 (-7925 1600);
DISPLAY INVISIBLE (-7925 1600);
FORCEPROP 1 LAST MATERIAL CHIP
J 0
(-7550 1525);
DISPLAY 0.638298 (-7550 1525);
FORCEPROP 1 LAST VALUE 0
J 2
(-7650 1525);
DISPLAY 0.638298 (-7650 1525);
FORCEPROP 1 LAST $LOCATION R3778
J 0
(-8000 1525);
DISPLAY 0.638298 (-8000 1525);
FORCEPROP 1 LASTPIN (-7900 1525) $PN 1
J 0
(-7888 1537);
DISPLAY 0.787234 (-7888 1537);
PAINT MONO (-7888 1537);
FORCEPROP 1 LASTPIN (-7700 1525) $PN 2
J 0
(-7738 1537);
DISPLAY 0.787234 (-7738 1537);
PAINT MONO (-7738 1537);
FORCEPROP 1 LAST WATTAGE 1/16W
J 2
(-7550 1650);
DISPLAY 0.638298 (-7550 1650);
DISPLAY INVISIBLE (-7550 1650);
FORCEPROP 1 LAST TOLERANCE 5%
J 0
(-7625 1525);
DISPLAY 0.638298 (-7625 1525);
DISPLAY INVISIBLE (-7625 1525);
FORCEPROP 1 LAST PACK_TYPE 0402LF
J 0
(-7925 1650);
DISPLAY 0.638298 (-7925 1650);
DISPLAY INVISIBLE (-7925 1650);
FORCEPROP 2 LAST CDS_LIB pure_quanta
J 0
(-7800 1525);
DISPLAY INVISIBLE (-7800 1525);
FORCEPROP 1 LAST PATH I159
J 0
(-7850 1675);
DISPLAY 0.978723 (-7850 1675);
PAINT WHITE (-7850 1675);
DISPLAY INVISIBLE (-7850 1675);
FORCEPROP 0 LAST CDS_LOCATION R3778
J 0
(-7550 1575);
DISPLAY 1.021277 (-7550 1575);
DISPLAY INVISIBLE (-7550 1575);
FORCEPROP 0 LAST $SEC 1
J 0
(-7550 1575);
DISPLAY 0.680851 (-7550 1575);
PAINT MONO (-7550 1575);
DISPLAY INVISIBLE (-7550 1575);
FORCEPROP 0 LAST CDS_SEC 1
J 0
(-7550 1575);
DISPLAY 1.021277 (-7550 1575);
DISPLAY INVISIBLE (-7550 1575);
FORCEADD OFFPAGE..1
(-14325 -975);
FORCEPROP 2 LAST $XR1 228 
J 0
(-14697 -975);
DISPLAY 0.638298 (-14697 -975);
PAINT MONO (-14697 -975);
FORCEPROP 2 LAST $XR0 214 
J 0
(-14577 -975);
DISPLAY 0.638298 (-14577 -975);
PAINT MONO (-14577 -975);
FORCEPROP 1 LAST COMMENT_BODY TRUE
J 0
(-14200 -1075);
DISPLAY 0.872340 (-14200 -1075);
PAINT PEACH (-14200 -1075);
DISPLAY INVISIBLE (-14200 -1075);
FORCEPROP 1 LAST OFFPAGE TRUE
J 0
(-14000 -1100);
DISPLAY 0.872340 (-14000 -1100);
PAINT GREEN (-14000 -1100);
DISPLAY INVISIBLE (-14000 -1100);
FORCEPROP 2 LAST CDS_LIB standard
J 0
(-14325 -975);
PAINT MONO (-14325 -975);
DISPLAY INVISIBLE (-14325 -975);
FORCEPROP 2 LAST PATH I16
J 0
(-14575 -925);
DISPLAY 1.021277 (-14575 -925);
DISPLAY INVISIBLE (-14575 -925);
FORCEADD UNIVERSAL_POWER..1
(-9550 2450);
FORCEPROP 3 LASTPIN (-9550 2400) SIG_NAME P12V_SCM\g
J 0
(-9540 2410);
DISPLAY 0.659574 (-9540 2410);
PAINT MONO (-9540 2410);
DISPLAY INVISIBLE (-9540 2410);
FORCEPROP 1 LAST HDL_POWER P12V_SCM
J 1
(-9550 2500);
DISPLAY 0.702128 (-9550 2500);
PAINT GREEN (-9550 2500);
FORCEPROP 2 LAST CDS_LIB logical_power
J 0
(-9550 2450);
DISPLAY INVISIBLE (-9550 2450);
FORCEPROP 1 LAST PATH I160
J 0
(-9500 2475);
DISPLAY 0.872340 (-9500 2475);
PAINT AQUA (-9500 2475);
DISPLAY INVISIBLE (-9500 2475);
FORCEADD OFFPAGE..4
(-8350 1625);
FORCEPROP 2 LAST $XR0 185 
J 0
(-8164 1625);
DISPLAY 0.638298 (-8164 1625);
PAINT MONO (-8164 1625);
FORCEPROP 1 LAST OFFPAGE TRUE
J 0
(-8025 1500);
DISPLAY 0.872340 (-8025 1500);
PAINT GREEN (-8025 1500);
DISPLAY INVISIBLE (-8025 1500);
FORCEPROP 1 LAST COMMENT_BODY TRUE
J 0
(-8375 1525);
DISPLAY 0.872340 (-8375 1525);
PAINT PEACH (-8375 1525);
DISPLAY INVISIBLE (-8375 1525);
FORCEPROP 2 LAST CDS_LIB standard
J 0
(-8350 1625);
PAINT MONO (-8350 1625);
DISPLAY INVISIBLE (-8350 1625);
FORCEPROP 2 LAST PATH I161
J 0
(-8150 1675);
DISPLAY 1.021277 (-8150 1675);
DISPLAY INVISIBLE (-8150 1675);
FORCEADD OFFPAGE..4
(-8350 1575);
FORCEPROP 2 LAST $XR0 226 
J 0
(-8164 1575);
DISPLAY 0.638298 (-8164 1575);
PAINT MONO (-8164 1575);
FORCEPROP 1 LAST OFFPAGE TRUE
J 0
(-8025 1450);
DISPLAY 0.872340 (-8025 1450);
PAINT GREEN (-8025 1450);
DISPLAY INVISIBLE (-8025 1450);
FORCEPROP 1 LAST COMMENT_BODY TRUE
J 0
(-8375 1475);
DISPLAY 0.872340 (-8375 1475);
PAINT PEACH (-8375 1475);
DISPLAY INVISIBLE (-8375 1475);
FORCEPROP 2 LAST CDS_LIB standard
J 0
(-8350 1575);
DISPLAY INVISIBLE (-8350 1575);
FORCEPROP 2 LAST PATH I162
J 0
(-8150 1625);
DISPLAY 1.021277 (-8150 1625);
DISPLAY INVISIBLE (-8150 1625);
FORCEADD OFFPAGE..4
(-8350 1675);
FORCEPROP 2 LAST $XR0 213 
J 0
(-8074 1675);
DISPLAY 0.638298 (-8074 1675);
PAINT MONO (-8074 1675);
FORCEPROP 2 LAST CDS_LIB standard
J 0
(-8350 1675);
DISPLAY INVISIBLE (-8350 1675);
FORCEPROP 1 LAST COMMENT_BODY TRUE
J 0
(-8375 1575);
DISPLAY 0.872340 (-8375 1575);
PAINT PEACH (-8375 1575);
DISPLAY INVISIBLE (-8375 1575);
FORCEPROP 1 LAST OFFPAGE TRUE
J 0
(-8025 1550);
DISPLAY 0.872340 (-8025 1550);
PAINT GREEN (-8025 1550);
DISPLAY INVISIBLE (-8025 1550);
FORCEPROP 2 LAST PATH I163
J 0
(-8050 1725);
DISPLAY 1.021277 (-8050 1725);
DISPLAY INVISIBLE (-8050 1725);
FORCEADD Q_RES..1
(-8175 1775);
FORCEPROP 1 LAST PART_NUMBER CS00002JB13
J 0
(-8300 1850);
DISPLAY 0.638298 (-8300 1850);
DISPLAY INVISIBLE (-8300 1850);
FORCEPROP 1 LAST VALUE 0
J 2
(-8025 1775);
DISPLAY 0.510638 (-8025 1775);
FORCEPROP 1 LAST TOLERANCE 5%
J 0
(-8000 1775);
DISPLAY 0.510638 (-8000 1775);
FORCEPROP 1 LAST MATERIAL EMPTY
J 0
(-7925 1775);
DISPLAY 0.510638 (-7925 1775);
PAINT RED (-7925 1775);
FORCEPROP 1 LAST $LOCATION R2257
J 0
(-8400 1775);
DISPLAY 0.638298 (-8400 1775);
FORCEPROP 1 LASTPIN (-8275 1775) $PN 1
J 0
(-8263 1787);
DISPLAY 0.787234 (-8263 1787);
PAINT MONO (-8263 1787);
FORCEPROP 1 LASTPIN (-8075 1775) $PN 2
J 0
(-8113 1787);
DISPLAY 0.787234 (-8113 1787);
PAINT MONO (-8113 1787);
FORCEPROP 1 LAST WATTAGE 1/16W
J 2
(-7925 1900);
DISPLAY 0.638298 (-7925 1900);
DISPLAY INVISIBLE (-7925 1900);
FORCEPROP 1 LAST PACK_TYPE 0402LF
J 0
(-8300 1900);
DISPLAY 0.638298 (-8300 1900);
DISPLAY INVISIBLE (-8300 1900);
FORCEPROP 2 LAST CDS_LIB pure_quanta
J 0
(-8175 1775);
DISPLAY INVISIBLE (-8175 1775);
FORCEPROP 1 LAST PATH I164
J 0
(-8225 1925);
DISPLAY 0.978723 (-8225 1925);
PAINT WHITE (-8225 1925);
DISPLAY INVISIBLE (-8225 1925);
FORCEPROP 0 LAST CDS_LOCATION R2257
J 0
(-8400 1825);
DISPLAY 1.021277 (-8400 1825);
DISPLAY INVISIBLE (-8400 1825);
FORCEPROP 0 LAST $SEC 1
J 0
(-8400 1825);
DISPLAY 0.680851 (-8400 1825);
PAINT MONO (-8400 1825);
DISPLAY INVISIBLE (-8400 1825);
FORCEPROP 0 LAST CDS_SEC 1
J 0
(-8400 1825);
DISPLAY 1.021277 (-8400 1825);
DISPLAY INVISIBLE (-8400 1825);
FORCEADD OFFPAGE..4
(-8350 1925);
FORCEPROP 2 LAST $XR0 151 
J 0
(-8164 1925);
DISPLAY 0.638298 (-8164 1925);
PAINT MONO (-8164 1925);
FORCEPROP 2 LAST CDS_LIB standard
J 0
(-8350 1925);
DISPLAY INVISIBLE (-8350 1925);
FORCEPROP 1 LAST COMMENT_BODY TRUE
J 0
(-8375 1825);
DISPLAY 0.872340 (-8375 1825);
PAINT PEACH (-8375 1825);
DISPLAY INVISIBLE (-8375 1825);
FORCEPROP 1 LAST OFFPAGE TRUE
J 0
(-8025 1800);
DISPLAY 0.872340 (-8025 1800);
PAINT GREEN (-8025 1800);
DISPLAY INVISIBLE (-8025 1800);
FORCEPROP 2 LAST PATH I165
J 0
(-8150 1975);
DISPLAY 1.021277 (-8150 1975);
DISPLAY INVISIBLE (-8150 1975);
FORCEADD OFFPAGE..2
(-8350 1975);
FORCEPROP 2 LAST $XR0 137 
J 0
(-8161 1975);
DISPLAY 0.638298 (-8161 1975);
PAINT MONO (-8161 1975);
FORCEPROP 2 LAST CDS_LIB standard
J 0
(-8350 1975);
DISPLAY INVISIBLE (-8350 1975);
FORCEPROP 1 LAST COMMENT_BODY TRUE
J 0
(-8395 1880);
DISPLAY 0.872340 (-8395 1880);
PAINT PEACH (-8395 1880);
DISPLAY INVISIBLE (-8395 1880);
FORCEPROP 1 LAST OFFPAGE TRUE
J 0
(-8025 1850);
DISPLAY 0.872340 (-8025 1850);
PAINT GREEN (-8025 1850);
DISPLAY INVISIBLE (-8025 1850);
FORCEPROP 2 LAST PATH I166
J 0
(-8150 2025);
DISPLAY 1.021277 (-8150 2025);
DISPLAY INVISIBLE (-8150 2025);
FORCEADD Q_RES..1
(-8175 1825);
FORCEPROP 1 LAST PART_NUMBER CS00002JB13
J 0
(-8700 1825);
DISPLAY 0.510638 (-8700 1825);
DISPLAY INVISIBLE (-8700 1825);
FORCEPROP 1 LAST PACK_TYPE 0402LF
J 0
(-8300 1725);
DISPLAY 0.510638 (-8300 1725);
FORCEPROP 1 LAST VALUE 0
J 2
(-8025 1825);
DISPLAY 0.510638 (-8025 1825);
FORCEPROP 1 LAST TOLERANCE 5%
J 0
(-8000 1825);
DISPLAY 0.510638 (-8000 1825);
FORCEPROP 1 LAST MATERIAL EMPTY
J 0
(-7925 1825);
DISPLAY 0.510638 (-7925 1825);
PAINT RED (-7925 1825);
FORCEPROP 1 LAST WATTAGE 1/16W
J 2
(-8025 1725);
DISPLAY 0.510638 (-8025 1725);
FORCEPROP 1 LAST $LOCATION R2256
J 0
(-8400 1825);
DISPLAY 0.638298 (-8400 1825);
FORCEPROP 1 LASTPIN (-8275 1825) $PN 1
J 0
(-8263 1837);
DISPLAY 0.787234 (-8263 1837);
PAINT MONO (-8263 1837);
FORCEPROP 1 LASTPIN (-8075 1825) $PN 2
J 0
(-8113 1837);
DISPLAY 0.787234 (-8113 1837);
PAINT MONO (-8113 1837);
FORCEPROP 2 LAST CDS_LIB pure_quanta
J 0
(-8175 1825);
DISPLAY INVISIBLE (-8175 1825);
FORCEPROP 1 LAST PATH I167
J 0
(-8225 1975);
DISPLAY 0.978723 (-8225 1975);
PAINT WHITE (-8225 1975);
DISPLAY INVISIBLE (-8225 1975);
FORCEPROP 0 LAST CDS_LOCATION R2256
J 0
(-8000 1950);
DISPLAY 1.021277 (-8000 1950);
DISPLAY INVISIBLE (-8000 1950);
FORCEPROP 0 LAST $SEC 1
J 0
(-8000 1950);
DISPLAY 0.680851 (-8000 1950);
PAINT MONO (-8000 1950);
DISPLAY INVISIBLE (-8000 1950);
FORCEPROP 0 LAST CDS_SEC 1
J 0
(-8000 1950);
DISPLAY 1.021277 (-8000 1950);
DISPLAY INVISIBLE (-8000 1950);
FORCEADD OFFPAGE..2
(-6725 1525);
FORCEPROP 2 LAST $XR0 214 
J 0
(-6536 1525);
DISPLAY 0.638298 (-6536 1525);
PAINT MONO (-6536 1525);
FORCEPROP 1 LAST OFFPAGE TRUE
J 0
(-6400 1400);
DISPLAY 0.872340 (-6400 1400);
PAINT GREEN (-6400 1400);
DISPLAY INVISIBLE (-6400 1400);
FORCEPROP 1 LAST COMMENT_BODY TRUE
J 0
(-6770 1430);
DISPLAY 0.872340 (-6770 1430);
PAINT PEACH (-6770 1430);
DISPLAY INVISIBLE (-6770 1430);
FORCEPROP 2 LAST CDS_LIB standard
J 0
(-6725 1525);
DISPLAY INVISIBLE (-6725 1525);
FORCEPROP 2 LAST PATH I168
J 0
(-6525 1575);
DISPLAY 1.021277 (-6525 1575);
DISPLAY INVISIBLE (-6525 1575);
FORCEADD OFFPAGE..3
(-7325 1775);
FORCEPROP 2 LAST $XR0 180 
J 0
(-7111 1775);
DISPLAY 0.638298 (-7111 1775);
PAINT MONO (-7111 1775);
FORCEPROP 1 LAST OFFPAGE TRUE
J 0
(-7000 1650);
DISPLAY 0.872340 (-7000 1650);
PAINT GREEN (-7000 1650);
DISPLAY INVISIBLE (-7000 1650);
FORCEPROP 1 LAST COMMENT_BODY TRUE
J 0
(-7375 1675);
DISPLAY 0.872340 (-7375 1675);
PAINT PEACH (-7375 1675);
DISPLAY INVISIBLE (-7375 1675);
FORCEPROP 2 LAST CDS_LIB standard
J 0
(-7325 1775);
DISPLAY INVISIBLE (-7325 1775);
FORCEPROP 2 LAST PATH I169
J 0
(-7100 1825);
DISPLAY 1.021277 (-7100 1825);
DISPLAY INVISIBLE (-7100 1825);
FORCEADD OFFPAGE..5
(-14325 -925);
FORCEPROP 2 LAST $XR0 214 
J 0
(-14580 -925);
DISPLAY 0.638298 (-14580 -925);
PAINT MONO (-14580 -925);
FORCEPROP 2 LAST CDS_LIB standard
J 0
(-14325 -925);
DISPLAY INVISIBLE (-14325 -925);
FORCEPROP 1 LAST OFFPAGE TRUE
J 0
(-14000 -1050);
DISPLAY 0.872340 (-14000 -1050);
PAINT GREEN (-14000 -1050);
DISPLAY INVISIBLE (-14000 -1050);
FORCEPROP 1 LAST COMMENT_BODY TRUE
J 0
(-14225 -1000);
DISPLAY 0.872340 (-14225 -1000);
PAINT PEACH (-14225 -1000);
DISPLAY INVISIBLE (-14225 -1000);
FORCEPROP 2 LAST PATH I17
J 0
(-14575 -875);
DISPLAY 1.021277 (-14575 -875);
DISPLAY INVISIBLE (-14575 -875);
FORCEADD OFFPAGE..3
(-7325 1825);
FORCEPROP 2 LAST $XR0 180 
J 0
(-7111 1825);
DISPLAY 0.638298 (-7111 1825);
PAINT MONO (-7111 1825);
FORCEPROP 1 LAST COMMENT_BODY TRUE
J 0
(-7375 1725);
DISPLAY 0.872340 (-7375 1725);
PAINT PEACH (-7375 1725);
DISPLAY INVISIBLE (-7375 1725);
FORCEPROP 1 LAST OFFPAGE TRUE
J 0
(-7000 1700);
DISPLAY 0.872340 (-7000 1700);
PAINT GREEN (-7000 1700);
DISPLAY INVISIBLE (-7000 1700);
FORCEPROP 2 LAST CDS_LIB standard
J 0
(-7325 1825);
DISPLAY INVISIBLE (-7325 1825);
FORCEPROP 2 LAST PATH I170
J 0
(-7100 1875);
DISPLAY 1.021277 (-7100 1875);
DISPLAY INVISIBLE (-7100 1875);
FORCEADD UNIVERSAL_GND..1
(-7625 2050);
FORCEPROP 3 LASTPIN (-7625 2100) SIG_NAME GND\g
J 0
(-7615 2110);
DISPLAY 0.659574 (-7615 2110);
PAINT MONO (-7615 2110);
DISPLAY INVISIBLE (-7615 2110);
FORCEPROP 1 LAST HDL_POWER GND
J 1
(-7600 1975);
DISPLAY 0.702128 (-7600 1975);
PAINT GREEN (-7600 1975);
DISPLAY INVISIBLE (-7600 1975);
FORCEPROP 2 LAST CDS_LIB logical_power
J 0
(-7625 2050);
DISPLAY INVISIBLE (-7625 2050);
FORCEPROP 1 LAST PATH I171
J 0
(-7550 2050);
DISPLAY 0.872340 (-7550 2050);
PAINT AQUA (-7550 2050);
DISPLAY INVISIBLE (-7550 2050);
FORCEADD Q_RES..2
(-7625 2250);
FORCEPROP 1 LAST PART_NUMBER CS00002JB13
J 0
(-7585 2125);
DISPLAY 0.638298 (-7585 2125);
DISPLAY INVISIBLE (-7585 2125);
FORCEPROP 1 LAST MATERIAL CHIP
J 0
(-7585 2175);
DISPLAY 0.638298 (-7585 2175);
FORCEPROP 1 LAST WATTAGE 1/16W
J 0
(-7585 2225);
DISPLAY 0.638298 (-7585 2225);
FORCEPROP 1 LAST PACK_TYPE 0402LF
J 0
(-7585 2075);
DISPLAY 0.638298 (-7585 2075);
FORCEPROP 1 LAST VALUE 0
J 0
(-7580 2325);
DISPLAY 0.638298 (-7580 2325);
FORCEPROP 1 LAST TOLERANCE 5%
J 0
(-7580 2275);
DISPLAY 0.638298 (-7580 2275);
FORCEPROP 1 LAST $LOCATION R1801
J 0
(-7580 2375);
DISPLAY 0.638298 (-7580 2375);
FORCEPROP 1 LASTPIN (-7625 2350) $PN 1
J 0
(-7620 2312);
DISPLAY 0.787234 (-7620 2312);
PAINT MONO (-7620 2312);
FORCEPROP 1 LASTPIN (-7625 2150) $PN 2
J 0
(-7620 2160);
DISPLAY 0.787234 (-7620 2160);
PAINT MONO (-7620 2160);
FORCEPROP 2 LAST CDS_LIB pure_quanta
J 0
(-7625 2250);
DISPLAY INVISIBLE (-7625 2250);
FORCEPROP 1 LAST PATH I172
J 0
(-7575 2425);
DISPLAY 0.978723 (-7575 2425);
PAINT WHITE (-7575 2425);
DISPLAY INVISIBLE (-7575 2425);
FORCEPROP 0 LAST CDS_LOCATION R1801
J 0
(-7575 2425);
DISPLAY 1.021277 (-7575 2425);
DISPLAY INVISIBLE (-7575 2425);
FORCEPROP 0 LAST $SEC 1
J 0
(-7575 2425);
DISPLAY 0.680851 (-7575 2425);
PAINT MONO (-7575 2425);
DISPLAY INVISIBLE (-7575 2425);
FORCEPROP 0 LAST CDS_SEC 1
J 0
(-7575 2425);
DISPLAY 1.021277 (-7575 2425);
DISPLAY INVISIBLE (-7575 2425);
FORCEADD SCONN168_ME1016810202011..1
R 2
(-10400 -200);
FORCEPROP 1 LAST PART_NUMBER DFHSG8FR011
J 2
(-9911 2420);
DISPLAY 0.723404 (-9911 2420);
PAINT GREEN (-9911 2420);
DISPLAY INVISIBLE (-9911 2420);
FORCEPROP 1 LAST MATERIAL IO
J 2
(-9911 2293);
DISPLAY 0.723404 (-9911 2293);
PAINT GREEN (-9911 2293);
FORCEPROP 2 LAST PART_TYPE SMLF
J 2
(-9925 2675);
DISPLAY 1.021277 (-9925 2675);
FORCEPROP 2 LAST VALUE SCONN168_ME1016810202011
J 2
(-9925 2625);
DISPLAY 1.021277 (-9925 2625);
FORCEPROP 1 LAST LOCATION J41
J 2
(-9911 2567);
DISPLAY 0.723404 (-9911 2567);
PAINT GREEN (-9911 2567);
FORCEPROP 2 LASTPIN (-9750 875) $PN B11
J 0
(-9740 885);
DISPLAY 0.680851 (-9740 885);
PAINT MONO (-9740 885);
FORCEPROP 2 LASTPIN (-9750 1375) $PN B1
J 0
(-9740 1385);
DISPLAY 0.680851 (-9740 1385);
PAINT MONO (-9740 1385);
FORCEPROP 2 LASTPIN (-9750 1325) $PN B2
J 0
(-9740 1335);
DISPLAY 0.680851 (-9740 1335);
PAINT MONO (-9740 1335);
FORCEPROP 2 LASTPIN (-9750 1275) $PN B3
J 0
(-9740 1285);
DISPLAY 0.680851 (-9740 1285);
PAINT MONO (-9740 1285);
FORCEPROP 2 LASTPIN (-9750 1225) $PN B4
J 0
(-9740 1235);
DISPLAY 0.680851 (-9740 1235);
PAINT MONO (-9740 1235);
FORCEPROP 2 LASTPIN (-9750 1175) $PN B5
J 0
(-9740 1185);
DISPLAY 0.680851 (-9740 1185);
PAINT MONO (-9740 1185);
FORCEPROP 2 LASTPIN (-9750 1125) $PN B6
J 0
(-9740 1135);
DISPLAY 0.680851 (-9740 1135);
PAINT MONO (-9740 1135);
FORCEPROP 2 LASTPIN (-9750 825) $PN B12
J 0
(-9740 835);
DISPLAY 0.680851 (-9740 835);
PAINT MONO (-9740 835);
FORCEPROP 2 LASTPIN (-9750 1075) $PN B7
J 0
(-9740 1085);
DISPLAY 0.680851 (-9740 1085);
PAINT MONO (-9740 1085);
FORCEPROP 2 LASTPIN (-9750 1025) $PN B8
J 0
(-9740 1035);
DISPLAY 0.680851 (-9740 1035);
PAINT MONO (-9740 1035);
FORCEPROP 2 LASTPIN (-9750 975) $PN B9
J 0
(-9740 985);
DISPLAY 0.680851 (-9740 985);
PAINT MONO (-9740 985);
FORCEPROP 2 LASTPIN (-9750 1925) $PN OB6
J 0
(-9740 1935);
DISPLAY 0.680851 (-9740 1935);
PAINT MONO (-9740 1935);
FORCEPROP 2 LASTPIN (-9750 2025) $PN OB4
J 0
(-9740 2035);
DISPLAY 0.680851 (-9740 2035);
PAINT MONO (-9740 2035);
FORCEPROP 2 LASTPIN (-9750 1975) $PN OB5
J 0
(-9740 1985);
DISPLAY 0.680851 (-9740 1985);
PAINT MONO (-9740 1985);
FORCEPROP 2 LASTPIN (-11050 -2375) $PN G1
J 2
(-11060 -2365);
DISPLAY 0.680851 (-11060 -2365);
PAINT MONO (-11060 -2365);
FORCEPROP 2 LASTPIN (-11050 -2425) $PN G2
J 2
(-11060 -2415);
DISPLAY 0.680851 (-11060 -2415);
PAINT MONO (-11060 -2415);
FORCEPROP 2 LASTPIN (-11050 -2475) $PN G3
J 2
(-11060 -2465);
DISPLAY 0.680851 (-11060 -2465);
PAINT MONO (-11060 -2465);
FORCEPROP 2 LASTPIN (-11050 -2525) $PN G4
J 2
(-11060 -2515);
DISPLAY 0.680851 (-11060 -2515);
PAINT MONO (-11060 -2515);
FORCEPROP 2 LASTPIN (-11050 -2575) $PN G5
J 2
(-11060 -2565);
DISPLAY 0.680851 (-11060 -2565);
PAINT MONO (-11060 -2565);
FORCEPROP 2 LASTPIN (-11050 1375) $PN A1
J 2
(-11060 1385);
DISPLAY 0.680851 (-11060 1385);
PAINT MONO (-11060 1385);
FORCEPROP 2 LASTPIN (-11050 1325) $PN A2
J 2
(-11060 1335);
DISPLAY 0.680851 (-11060 1335);
PAINT MONO (-11060 1335);
FORCEPROP 2 LASTPIN (-11050 1275) $PN A3
J 2
(-11060 1285);
DISPLAY 0.680851 (-11060 1285);
PAINT MONO (-11060 1285);
FORCEPROP 2 LASTPIN (-11050 1225) $PN A4
J 2
(-11060 1235);
DISPLAY 0.680851 (-11060 1235);
PAINT MONO (-11060 1235);
FORCEPROP 2 LASTPIN (-11050 1175) $PN A5
J 2
(-11060 1185);
DISPLAY 0.680851 (-11060 1185);
PAINT MONO (-11060 1185);
FORCEPROP 2 LASTPIN (-11050 1125) $PN A6
J 2
(-11060 1135);
DISPLAY 0.680851 (-11060 1135);
PAINT MONO (-11060 1135);
FORCEPROP 2 LASTPIN (-11050 775) $PN A13
J 2
(-11060 785);
DISPLAY 0.680851 (-11060 785);
PAINT MONO (-11060 785);
FORCEPROP 2 LASTPIN (-11050 625) $PN A16
J 2
(-11060 635);
DISPLAY 0.680851 (-11060 635);
PAINT MONO (-11060 635);
FORCEPROP 2 LASTPIN (-11050 475) $PN A19
J 2
(-11060 485);
DISPLAY 0.680851 (-11060 485);
PAINT MONO (-11060 485);
FORCEPROP 2 LASTPIN (-11050 325) $PN A22
J 2
(-11060 335);
DISPLAY 0.680851 (-11060 335);
PAINT MONO (-11060 335);
FORCEPROP 2 LASTPIN (-11050 175) $PN A25
J 2
(-11060 185);
DISPLAY 0.680851 (-11060 185);
PAINT MONO (-11060 185);
FORCEPROP 2 LASTPIN (-11050 25) $PN A28
J 2
(-11060 35);
DISPLAY 0.680851 (-11060 35);
PAINT MONO (-11060 35);
FORCEPROP 2 LASTPIN (-11050 -125) $PN A29
J 2
(-11060 -115);
DISPLAY 0.680851 (-11060 -115);
PAINT MONO (-11060 -115);
FORCEPROP 2 LASTPIN (-11050 -275) $PN A32
J 2
(-11060 -265);
DISPLAY 0.680851 (-11060 -265);
PAINT MONO (-11060 -265);
FORCEPROP 2 LASTPIN (-11050 -425) $PN A35
J 2
(-11060 -415);
DISPLAY 0.680851 (-11060 -415);
PAINT MONO (-11060 -415);
FORCEPROP 2 LASTPIN (-11050 -575) $PN A38
J 2
(-11060 -565);
DISPLAY 0.680851 (-11060 -565);
PAINT MONO (-11060 -565);
FORCEPROP 2 LASTPIN (-11050 -725) $PN A41
J 2
(-11060 -715);
DISPLAY 0.680851 (-11060 -715);
PAINT MONO (-11060 -715);
FORCEPROP 2 LASTPIN (-11050 -925) $PN A43
J 2
(-11060 -915);
DISPLAY 0.680851 (-11060 -915);
PAINT MONO (-11060 -915);
FORCEPROP 2 LASTPIN (-11050 -1075) $PN A46
J 2
(-11060 -1065);
DISPLAY 0.680851 (-11060 -1065);
PAINT MONO (-11060 -1065);
FORCEPROP 2 LASTPIN (-11050 -1225) $PN A49
J 2
(-11060 -1215);
DISPLAY 0.680851 (-11060 -1215);
PAINT MONO (-11060 -1215);
FORCEPROP 2 LASTPIN (-11050 -1375) $PN A52
J 2
(-11060 -1365);
DISPLAY 0.680851 (-11060 -1365);
PAINT MONO (-11060 -1365);
FORCEPROP 2 LASTPIN (-11050 -1525) $PN A55
J 2
(-11060 -1515);
DISPLAY 0.680851 (-11060 -1515);
PAINT MONO (-11060 -1515);
FORCEPROP 2 LASTPIN (-11050 -1675) $PN A58
J 2
(-11060 -1665);
DISPLAY 0.680851 (-11060 -1665);
PAINT MONO (-11060 -1665);
FORCEPROP 2 LASTPIN (-11050 -1825) $PN A61
J 2
(-11060 -1815);
DISPLAY 0.680851 (-11060 -1815);
PAINT MONO (-11060 -1815);
FORCEPROP 2 LASTPIN (-11050 -1975) $PN A64
J 2
(-11060 -1965);
DISPLAY 0.680851 (-11060 -1965);
PAINT MONO (-11060 -1965);
FORCEPROP 2 LASTPIN (-11050 -2125) $PN A67
J 2
(-11060 -2115);
DISPLAY 0.680851 (-11060 -2115);
PAINT MONO (-11060 -2115);
FORCEPROP 2 LASTPIN (-9750 775) $PN B13
J 0
(-9740 785);
DISPLAY 0.680851 (-9740 785);
PAINT MONO (-9740 785);
FORCEPROP 2 LASTPIN (-9750 625) $PN B16
J 0
(-9740 635);
DISPLAY 0.680851 (-9740 635);
PAINT MONO (-9740 635);
FORCEPROP 2 LASTPIN (-9750 475) $PN B19
J 0
(-9740 485);
DISPLAY 0.680851 (-9740 485);
PAINT MONO (-9740 485);
FORCEPROP 2 LASTPIN (-9750 325) $PN B22
J 0
(-9740 335);
DISPLAY 0.680851 (-9740 335);
PAINT MONO (-9740 335);
FORCEPROP 2 LASTPIN (-9750 175) $PN B25
J 0
(-9740 185);
DISPLAY 0.680851 (-9740 185);
PAINT MONO (-9740 185);
FORCEPROP 2 LASTPIN (-9750 25) $PN B28
J 0
(-9740 35);
DISPLAY 0.680851 (-9740 35);
PAINT MONO (-9740 35);
FORCEPROP 2 LASTPIN (-9750 -125) $PN B29
J 0
(-9740 -115);
DISPLAY 0.680851 (-9740 -115);
PAINT MONO (-9740 -115);
FORCEPROP 2 LASTPIN (-9750 -275) $PN B32
J 0
(-9740 -265);
DISPLAY 0.680851 (-9740 -265);
PAINT MONO (-9740 -265);
FORCEPROP 2 LASTPIN (-9750 -425) $PN B35
J 0
(-9740 -415);
DISPLAY 0.680851 (-9740 -415);
PAINT MONO (-9740 -415);
FORCEPROP 2 LASTPIN (-9750 -575) $PN B38
J 0
(-9740 -565);
DISPLAY 0.680851 (-9740 -565);
PAINT MONO (-9740 -565);
FORCEPROP 2 LASTPIN (-9750 -725) $PN B41
J 0
(-9740 -715);
DISPLAY 0.680851 (-9740 -715);
PAINT MONO (-9740 -715);
FORCEPROP 2 LASTPIN (-9750 -925) $PN B43
J 0
(-9740 -915);
DISPLAY 0.680851 (-9740 -915);
PAINT MONO (-9740 -915);
FORCEPROP 2 LASTPIN (-9750 -1075) $PN B46
J 0
(-9740 -1065);
DISPLAY 0.680851 (-9740 -1065);
PAINT MONO (-9740 -1065);
FORCEPROP 2 LASTPIN (-9750 -1225) $PN B49
J 0
(-9740 -1215);
DISPLAY 0.680851 (-9740 -1215);
PAINT MONO (-9740 -1215);
FORCEPROP 2 LASTPIN (-9750 -1375) $PN B52
J 0
(-9740 -1365);
DISPLAY 0.680851 (-9740 -1365);
PAINT MONO (-9740 -1365);
FORCEPROP 2 LASTPIN (-9750 -1525) $PN B55
J 0
(-9740 -1515);
DISPLAY 0.680851 (-9740 -1515);
PAINT MONO (-9740 -1515);
FORCEPROP 2 LASTPIN (-9750 -1675) $PN B58
J 0
(-9740 -1665);
DISPLAY 0.680851 (-9740 -1665);
PAINT MONO (-9740 -1665);
FORCEPROP 2 LASTPIN (-9750 -1825) $PN B61
J 0
(-9740 -1815);
DISPLAY 0.680851 (-9740 -1815);
PAINT MONO (-9740 -1815);
FORCEPROP 2 LASTPIN (-9750 -1975) $PN B64
J 0
(-9740 -1965);
DISPLAY 0.680851 (-9740 -1965);
PAINT MONO (-9740 -1965);
FORCEPROP 2 LASTPIN (-9750 -2125) $PN B67
J 0
(-9740 -2115);
DISPLAY 0.680851 (-9740 -2115);
PAINT MONO (-9740 -2115);
FORCEPROP 2 LASTPIN (-11050 1725) $PN OA10
J 2
(-11060 1735);
DISPLAY 0.680851 (-11060 1735);
PAINT MONO (-11060 1735);
FORCEPROP 2 LASTPIN (-11050 1575) $PN OA13
J 2
(-11060 1585);
DISPLAY 0.680851 (-11060 1585);
PAINT MONO (-11060 1585);
FORCEPROP 2 LASTPIN (-9750 1725) $PN OB10
J 0
(-9740 1735);
DISPLAY 0.680851 (-9740 1735);
PAINT MONO (-9740 1735);
FORCEPROP 2 LASTPIN (-9750 1575) $PN OB13
J 0
(-9740 1585);
DISPLAY 0.680851 (-9740 1585);
PAINT MONO (-9740 1585);
FORCEPROP 2 LASTPIN (-9750 2075) $PN OB3
J 0
(-9740 2085);
DISPLAY 0.680851 (-9740 2085);
PAINT MONO (-9740 2085);
FORCEPROP 2 LASTPIN (-9750 2125) $PN OB2
J 0
(-9740 2135);
DISPLAY 0.680851 (-9740 2135);
PAINT MONO (-9740 2135);
FORCEPROP 2 LASTPIN (-9750 2175) $PN OB1
J 0
(-9740 2185);
DISPLAY 0.680851 (-9740 2185);
PAINT MONO (-9740 2185);
FORCEPROP 2 LASTPIN (-11050 575) $PN A17
J 2
(-11060 585);
DISPLAY 0.680851 (-11060 585);
PAINT MONO (-11060 585);
FORCEPROP 2 LASTPIN (-11050 425) $PN A20
J 2
(-11060 435);
DISPLAY 0.680851 (-11060 435);
PAINT MONO (-11060 435);
FORCEPROP 2 LASTPIN (-11050 275) $PN A23
J 2
(-11060 285);
DISPLAY 0.680851 (-11060 285);
PAINT MONO (-11060 285);
FORCEPROP 2 LASTPIN (-11050 125) $PN A26
J 2
(-11060 135);
DISPLAY 0.680851 (-11060 135);
PAINT MONO (-11060 135);
FORCEPROP 2 LASTPIN (-11050 -175) $PN A30
J 2
(-11060 -165);
DISPLAY 0.680851 (-11060 -165);
PAINT MONO (-11060 -165);
FORCEPROP 2 LASTPIN (-11050 -325) $PN A33
J 2
(-11060 -315);
DISPLAY 0.680851 (-11060 -315);
PAINT MONO (-11060 -315);
FORCEPROP 2 LASTPIN (-11050 -475) $PN A36
J 2
(-11060 -465);
DISPLAY 0.680851 (-11060 -465);
PAINT MONO (-11060 -465);
FORCEPROP 2 LASTPIN (-11050 -625) $PN A39
J 2
(-11060 -615);
DISPLAY 0.680851 (-11060 -615);
PAINT MONO (-11060 -615);
FORCEPROP 2 LASTPIN (-11050 -975) $PN A44
J 2
(-11060 -965);
DISPLAY 0.680851 (-11060 -965);
PAINT MONO (-11060 -965);
FORCEPROP 2 LASTPIN (-11050 -1125) $PN A47
J 2
(-11060 -1115);
DISPLAY 0.680851 (-11060 -1115);
PAINT MONO (-11060 -1115);
FORCEPROP 2 LASTPIN (-11050 -1275) $PN A50
J 2
(-11060 -1265);
DISPLAY 0.680851 (-11060 -1265);
PAINT MONO (-11060 -1265);
FORCEPROP 2 LASTPIN (-11050 -1425) $PN A53
J 2
(-11060 -1415);
DISPLAY 0.680851 (-11060 -1415);
PAINT MONO (-11060 -1415);
FORCEPROP 2 LASTPIN (-11050 -1575) $PN A56
J 2
(-11060 -1565);
DISPLAY 0.680851 (-11060 -1565);
PAINT MONO (-11060 -1565);
FORCEPROP 2 LASTPIN (-11050 -1725) $PN A59
J 2
(-11060 -1715);
DISPLAY 0.680851 (-11060 -1715);
PAINT MONO (-11060 -1715);
FORCEPROP 2 LASTPIN (-11050 -1875) $PN A62
J 2
(-11060 -1865);
DISPLAY 0.680851 (-11060 -1865);
PAINT MONO (-11060 -1865);
FORCEPROP 2 LASTPIN (-11050 -2025) $PN A65
J 2
(-11060 -2015);
DISPLAY 0.680851 (-11060 -2015);
PAINT MONO (-11060 -2015);
FORCEPROP 2 LASTPIN (-11050 525) $PN A18
J 2
(-11060 535);
DISPLAY 0.680851 (-11060 535);
PAINT MONO (-11060 535);
FORCEPROP 2 LASTPIN (-11050 375) $PN A21
J 2
(-11060 385);
DISPLAY 0.680851 (-11060 385);
PAINT MONO (-11060 385);
FORCEPROP 2 LASTPIN (-11050 225) $PN A24
J 2
(-11060 235);
DISPLAY 0.680851 (-11060 235);
PAINT MONO (-11060 235);
FORCEPROP 2 LASTPIN (-11050 75) $PN A27
J 2
(-11060 85);
DISPLAY 0.680851 (-11060 85);
PAINT MONO (-11060 85);
FORCEPROP 2 LASTPIN (-11050 -225) $PN A31
J 2
(-11060 -215);
DISPLAY 0.680851 (-11060 -215);
PAINT MONO (-11060 -215);
FORCEPROP 2 LASTPIN (-11050 -375) $PN A34
J 2
(-11060 -365);
DISPLAY 0.680851 (-11060 -365);
PAINT MONO (-11060 -365);
FORCEPROP 2 LASTPIN (-11050 -525) $PN A37
J 2
(-11060 -515);
DISPLAY 0.680851 (-11060 -515);
PAINT MONO (-11060 -515);
FORCEPROP 2 LASTPIN (-11050 -675) $PN A40
J 2
(-11060 -665);
DISPLAY 0.680851 (-11060 -665);
PAINT MONO (-11060 -665);
FORCEPROP 2 LASTPIN (-11050 -1025) $PN A45
J 2
(-11060 -1015);
DISPLAY 0.680851 (-11060 -1015);
PAINT MONO (-11060 -1015);
FORCEPROP 2 LASTPIN (-11050 -1175) $PN A48
J 2
(-11060 -1165);
DISPLAY 0.680851 (-11060 -1165);
PAINT MONO (-11060 -1165);
FORCEPROP 2 LASTPIN (-11050 -1325) $PN A51
J 2
(-11060 -1315);
DISPLAY 0.680851 (-11060 -1315);
PAINT MONO (-11060 -1315);
FORCEPROP 2 LASTPIN (-11050 -1475) $PN A54
J 2
(-11060 -1465);
DISPLAY 0.680851 (-11060 -1465);
PAINT MONO (-11060 -1465);
FORCEPROP 2 LASTPIN (-11050 -1625) $PN A57
J 2
(-11060 -1615);
DISPLAY 0.680851 (-11060 -1615);
PAINT MONO (-11060 -1615);
FORCEPROP 2 LASTPIN (-11050 -1775) $PN A60
J 2
(-11060 -1765);
DISPLAY 0.680851 (-11060 -1765);
PAINT MONO (-11060 -1765);
FORCEPROP 2 LASTPIN (-11050 -1925) $PN A63
J 2
(-11060 -1915);
DISPLAY 0.680851 (-11060 -1915);
PAINT MONO (-11060 -1915);
FORCEPROP 2 LASTPIN (-11050 -2075) $PN A66
J 2
(-11060 -2065);
DISPLAY 0.680851 (-11060 -2065);
PAINT MONO (-11060 -2065);
FORCEPROP 2 LASTPIN (-9750 925) $PN B10
J 0
(-9740 935);
DISPLAY 0.680851 (-9740 935);
PAINT MONO (-9740 935);
FORCEPROP 2 LASTPIN (-11050 875) $PN A11
J 2
(-11060 885);
DISPLAY 0.680851 (-11060 885);
PAINT MONO (-11060 885);
FORCEPROP 2 LASTPIN (-11050 2175) $PN OA1
J 2
(-11060 2185);
DISPLAY 0.680851 (-11060 2185);
PAINT MONO (-11060 2185);
FORCEPROP 2 LASTPIN (-11050 2125) $PN OA2
J 2
(-11060 2135);
DISPLAY 0.680851 (-11060 2135);
PAINT MONO (-11060 2135);
FORCEPROP 2 LASTPIN (-9750 575) $PN B17
J 0
(-9740 585);
DISPLAY 0.680851 (-9740 585);
PAINT MONO (-9740 585);
FORCEPROP 2 LASTPIN (-9750 425) $PN B20
J 0
(-9740 435);
DISPLAY 0.680851 (-9740 435);
PAINT MONO (-9740 435);
FORCEPROP 2 LASTPIN (-9750 275) $PN B23
J 0
(-9740 285);
DISPLAY 0.680851 (-9740 285);
PAINT MONO (-9740 285);
FORCEPROP 2 LASTPIN (-9750 125) $PN B26
J 0
(-9740 135);
DISPLAY 0.680851 (-9740 135);
PAINT MONO (-9740 135);
FORCEPROP 2 LASTPIN (-9750 -175) $PN B30
J 0
(-9740 -165);
DISPLAY 0.680851 (-9740 -165);
PAINT MONO (-9740 -165);
FORCEPROP 2 LASTPIN (-9750 -325) $PN B33
J 0
(-9740 -315);
DISPLAY 0.680851 (-9740 -315);
PAINT MONO (-9740 -315);
FORCEPROP 2 LASTPIN (-9750 -475) $PN B36
J 0
(-9740 -465);
DISPLAY 0.680851 (-9740 -465);
PAINT MONO (-9740 -465);
FORCEPROP 2 LASTPIN (-9750 -625) $PN B39
J 0
(-9740 -615);
DISPLAY 0.680851 (-9740 -615);
PAINT MONO (-9740 -615);
FORCEPROP 2 LASTPIN (-9750 -975) $PN B44
J 0
(-9740 -965);
DISPLAY 0.680851 (-9740 -965);
PAINT MONO (-9740 -965);
FORCEPROP 2 LASTPIN (-9750 -1125) $PN B47
J 0
(-9740 -1115);
DISPLAY 0.680851 (-9740 -1115);
PAINT MONO (-9740 -1115);
FORCEPROP 2 LASTPIN (-9750 -1275) $PN B50
J 0
(-9740 -1265);
DISPLAY 0.680851 (-9740 -1265);
PAINT MONO (-9740 -1265);
FORCEPROP 2 LASTPIN (-9750 -1425) $PN B53
J 0
(-9740 -1415);
DISPLAY 0.680851 (-9740 -1415);
PAINT MONO (-9740 -1415);
FORCEPROP 2 LASTPIN (-9750 -1575) $PN B56
J 0
(-9740 -1565);
DISPLAY 0.680851 (-9740 -1565);
PAINT MONO (-9740 -1565);
FORCEPROP 2 LASTPIN (-9750 -1725) $PN B59
J 0
(-9740 -1715);
DISPLAY 0.680851 (-9740 -1715);
PAINT MONO (-9740 -1715);
FORCEPROP 2 LASTPIN (-9750 -1875) $PN B62
J 0
(-9740 -1865);
DISPLAY 0.680851 (-9740 -1865);
PAINT MONO (-9740 -1865);
FORCEPROP 2 LASTPIN (-9750 -2025) $PN B65
J 0
(-9740 -2015);
DISPLAY 0.680851 (-9740 -2015);
PAINT MONO (-9740 -2015);
FORCEPROP 2 LASTPIN (-9750 525) $PN B18
J 0
(-9740 535);
DISPLAY 0.680851 (-9740 535);
PAINT MONO (-9740 535);
FORCEPROP 2 LASTPIN (-9750 375) $PN B21
J 0
(-9740 385);
DISPLAY 0.680851 (-9740 385);
PAINT MONO (-9740 385);
FORCEPROP 2 LASTPIN (-9750 225) $PN B24
J 0
(-9740 235);
DISPLAY 0.680851 (-9740 235);
PAINT MONO (-9740 235);
FORCEPROP 2 LASTPIN (-9750 75) $PN B27
J 0
(-9740 85);
DISPLAY 0.680851 (-9740 85);
PAINT MONO (-9740 85);
FORCEPROP 2 LASTPIN (-9750 -225) $PN B31
J 0
(-9740 -215);
DISPLAY 0.680851 (-9740 -215);
PAINT MONO (-9740 -215);
FORCEPROP 2 LASTPIN (-9750 -375) $PN B34
J 0
(-9740 -365);
DISPLAY 0.680851 (-9740 -365);
PAINT MONO (-9740 -365);
FORCEPROP 2 LASTPIN (-9750 -525) $PN B37
J 0
(-9740 -515);
DISPLAY 0.680851 (-9740 -515);
PAINT MONO (-9740 -515);
FORCEPROP 2 LASTPIN (-9750 -675) $PN B40
J 0
(-9740 -665);
DISPLAY 0.680851 (-9740 -665);
PAINT MONO (-9740 -665);
FORCEPROP 2 LASTPIN (-9750 -1025) $PN B45
J 0
(-9740 -1015);
DISPLAY 0.680851 (-9740 -1015);
PAINT MONO (-9740 -1015);
FORCEPROP 2 LASTPIN (-9750 -1175) $PN B48
J 0
(-9740 -1165);
DISPLAY 0.680851 (-9740 -1165);
PAINT MONO (-9740 -1165);
FORCEPROP 2 LASTPIN (-9750 -1325) $PN B51
J 0
(-9740 -1315);
DISPLAY 0.680851 (-9740 -1315);
PAINT MONO (-9740 -1315);
FORCEPROP 2 LASTPIN (-9750 -1475) $PN B54
J 0
(-9740 -1465);
DISPLAY 0.680851 (-9740 -1465);
PAINT MONO (-9740 -1465);
FORCEPROP 2 LASTPIN (-9750 -1625) $PN B57
J 0
(-9740 -1615);
DISPLAY 0.680851 (-9740 -1615);
PAINT MONO (-9740 -1615);
FORCEPROP 2 LASTPIN (-9750 -1775) $PN B60
J 0
(-9740 -1765);
DISPLAY 0.680851 (-9740 -1765);
PAINT MONO (-9740 -1765);
FORCEPROP 2 LASTPIN (-9750 -1925) $PN B63
J 0
(-9740 -1915);
DISPLAY 0.680851 (-9740 -1915);
PAINT MONO (-9740 -1915);
FORCEPROP 2 LASTPIN (-9750 -2075) $PN B66
J 0
(-9740 -2065);
DISPLAY 0.680851 (-9740 -2065);
PAINT MONO (-9740 -2065);
FORCEPROP 2 LASTPIN (-11050 925) $PN A10
J 2
(-11060 935);
DISPLAY 0.680851 (-11060 935);
PAINT MONO (-11060 935);
FORCEPROP 2 LASTPIN (-9750 -775) $PN B42
J 0
(-9740 -765);
DISPLAY 0.680851 (-9740 -765);
PAINT MONO (-9740 -765);
FORCEPROP 2 LASTPIN (-11050 -775) $PN A42
J 2
(-11060 -765);
DISPLAY 0.680851 (-11060 -765);
PAINT MONO (-11060 -765);
FORCEPROP 2 LASTPIN (-11050 825) $PN A12
J 2
(-11060 835);
DISPLAY 0.680851 (-11060 835);
PAINT MONO (-11060 835);
FORCEPROP 2 LASTPIN (-9750 -2275) $PN B70
J 0
(-9740 -2265);
DISPLAY 0.680851 (-9740 -2265);
PAINT MONO (-9740 -2265);
FORCEPROP 2 LASTPIN (-11050 -2275) $PN A70
J 2
(-11060 -2265);
DISPLAY 0.680851 (-11060 -2265);
PAINT MONO (-11060 -2265);
FORCEPROP 2 LASTPIN (-11050 2025) $PN OA4
J 2
(-11060 2035);
DISPLAY 0.680851 (-11060 2035);
PAINT MONO (-11060 2035);
FORCEPROP 2 LASTPIN (-11050 1975) $PN OA5
J 2
(-11060 1985);
DISPLAY 0.680851 (-11060 1985);
PAINT MONO (-11060 1985);
FORCEPROP 2 LASTPIN (-11050 1525) $PN OA14
J 2
(-11060 1535);
DISPLAY 0.680851 (-11060 1535);
PAINT MONO (-11060 1535);
FORCEPROP 2 LASTPIN (-9750 1525) $PN OB14
J 0
(-9740 1535);
DISPLAY 0.680851 (-9740 1535);
PAINT MONO (-9740 1535);
FORCEPROP 2 LASTPIN (-9750 1775) $PN OB9
J 0
(-9740 1785);
DISPLAY 0.680851 (-9740 1785);
PAINT MONO (-9740 1785);
FORCEPROP 2 LASTPIN (-9750 1825) $PN OB8
J 0
(-9740 1835);
DISPLAY 0.680851 (-9740 1835);
PAINT MONO (-9740 1835);
FORCEPROP 2 LASTPIN (-11050 1875) $PN OA7
J 2
(-11060 1885);
DISPLAY 0.680851 (-11060 1885);
PAINT MONO (-11060 1885);
FORCEPROP 2 LASTPIN (-11050 1775) $PN OA9
J 2
(-11060 1785);
DISPLAY 0.680851 (-11060 1785);
PAINT MONO (-11060 1785);
FORCEPROP 2 LASTPIN (-11050 1825) $PN OA8
J 2
(-11060 1835);
DISPLAY 0.680851 (-11060 1835);
PAINT MONO (-11060 1835);
FORCEPROP 2 LASTPIN (-9750 725) $PN B14
J 0
(-9740 735);
DISPLAY 0.680851 (-9740 735);
PAINT MONO (-9740 735);
FORCEPROP 2 LASTPIN (-11050 725) $PN A14
J 2
(-11060 735);
DISPLAY 0.680851 (-11060 735);
PAINT MONO (-11060 735);
FORCEPROP 2 LASTPIN (-9750 1675) $PN OB11
J 0
(-9740 1685);
DISPLAY 0.680851 (-9740 1685);
PAINT MONO (-9740 1685);
FORCEPROP 2 LASTPIN (-11050 1675) $PN OA11
J 2
(-11060 1685);
DISPLAY 0.680851 (-11060 1685);
PAINT MONO (-11060 1685);
FORCEPROP 2 LASTPIN (-9750 675) $PN B15
J 0
(-9740 685);
DISPLAY 0.680851 (-9740 685);
PAINT MONO (-9740 685);
FORCEPROP 2 LASTPIN (-11050 675) $PN A15
J 2
(-11060 685);
DISPLAY 0.680851 (-11060 685);
PAINT MONO (-11060 685);
FORCEPROP 2 LASTPIN (-9750 1625) $PN OB12
J 0
(-9740 1635);
DISPLAY 0.680851 (-9740 1635);
PAINT MONO (-9740 1635);
FORCEPROP 2 LASTPIN (-11050 1625) $PN OA12
J 2
(-11060 1635);
DISPLAY 0.680851 (-11060 1635);
PAINT MONO (-11060 1635);
FORCEPROP 2 LASTPIN (-9750 -2175) $PN B68
J 0
(-9740 -2165);
DISPLAY 0.680851 (-9740 -2165);
PAINT MONO (-9740 -2165);
FORCEPROP 2 LASTPIN (-9750 -2225) $PN B69
J 0
(-9740 -2215);
DISPLAY 0.680851 (-9740 -2215);
PAINT MONO (-9740 -2215);
FORCEPROP 2 LASTPIN (-9750 1875) $PN OB7
J 0
(-9740 1885);
DISPLAY 0.680851 (-9740 1885);
PAINT MONO (-9740 1885);
FORCEPROP 2 LASTPIN (-11050 1925) $PN OA6
J 2
(-11060 1935);
DISPLAY 0.680851 (-11060 1935);
PAINT MONO (-11060 1935);
FORCEPROP 2 LASTPIN (-11050 1075) $PN A7
J 2
(-11060 1085);
DISPLAY 0.680851 (-11060 1085);
PAINT MONO (-11060 1085);
FORCEPROP 2 LASTPIN (-11050 1025) $PN A8
J 2
(-11060 1035);
DISPLAY 0.680851 (-11060 1035);
PAINT MONO (-11060 1035);
FORCEPROP 2 LASTPIN (-11050 975) $PN A9
J 2
(-11060 985);
DISPLAY 0.680851 (-11060 985);
PAINT MONO (-11060 985);
FORCEPROP 2 LASTPIN (-11050 -2175) $PN A68
J 2
(-11060 -2165);
DISPLAY 0.680851 (-11060 -2165);
PAINT MONO (-11060 -2165);
FORCEPROP 2 LASTPIN (-11050 -2225) $PN A69
J 2
(-11060 -2215);
DISPLAY 0.680851 (-11060 -2215);
PAINT MONO (-11060 -2215);
FORCEPROP 2 LASTPIN (-11050 2075) $PN OA3
J 2
(-11060 2085);
DISPLAY 0.680851 (-11060 2085);
PAINT MONO (-11060 2085);
FORCEPROP 2 LAST SEC_TYPE 
J 2
(-9925 2725);
DISPLAY 1.021277 (-9925 2725);
DISPLAY INVISIBLE (-9925 2725);
FORCEPROP 1 LAST CDS_LMAN_SYM_OUTLINE -500,2475,500,-2475
J 2
(-10400 -200);
DISPLAY 0.468085 (-10400 -200);
PAINT GREEN (-10400 -200);
DISPLAY INVISIBLE (-10400 -200);
FORCEPROP 1 LAST NEEDS_NO_SIZE TRUE
J 2
(-10400 -200);
DISPLAY 0.723404 (-10400 -200);
PAINT GREEN (-10400 -200);
DISPLAY INVISIBLE (-10400 -200);
FORCEPROP 2 LAST CDS_LIB pure_quanta
J 2
(-10400 -200);
DISPLAY INVISIBLE (-10400 -200);
FORCEPROP 1 LAST PATH I173
J 2
(-10400 -200);
DISPLAY 0.723404 (-10400 -200);
PAINT GREEN (-10400 -200);
DISPLAY INVISIBLE (-10400 -200);
FORCEPROP 2 LAST SEC 1
J 2
(-9925 2725);
DISPLAY 0.680851 (-9925 2725);
PAINT MONO (-9925 2725);
DISPLAY INVISIBLE (-9925 2725);
FORCEADD Q_RES..1
(-13325 -1575);
FORCEPROP 1 LAST PART_NUMBER CS00002JB13
J 0
(-13475 -1525);
DISPLAY 0.510638 (-13475 -1525);
DISPLAY INVISIBLE (-13475 -1525);
FORCEPROP 1 LAST TOLERANCE 5%
J 0
(-13150 -1575);
DISPLAY 0.510638 (-13150 -1575);
FORCEPROP 1 LAST VALUE 0
J 2
(-13175 -1575);
DISPLAY 0.510638 (-13175 -1575);
FORCEPROP 1 LAST MATERIAL CHIP
J 0
(-13075 -1575);
DISPLAY 0.510638 (-13075 -1575);
FORCEPROP 1 LAST $LOCATION R506
J 0
(-13550 -1575);
DISPLAY 0.702128 (-13550 -1575);
FORCEPROP 1 LAST WATTAGE 1/16W
J 2
(-13175 -1475);
DISPLAY 0.510638 (-13175 -1475);
DISPLAY INVISIBLE (-13175 -1475);
FORCEPROP 1 LAST PACK_TYPE 0402LF
J 0
(-13475 -1475);
DISPLAY 0.510638 (-13475 -1475);
DISPLAY INVISIBLE (-13475 -1475);
FORCEPROP 2 LAST CDS_LIB pure_quanta
J 0
(-13325 -1481);
DISPLAY INVISIBLE (-13325 -1481);
FORCEPROP 1 LAST PATH I18
J 0
(-13375 -1425);
DISPLAY 0.978723 (-13375 -1425);
PAINT WHITE (-13375 -1425);
DISPLAY INVISIBLE (-13375 -1425);
FORCEPROP 2 LAST CDS_LOCATION R506
J 2
(-13375 -1375);
DISPLAY 1.021277 (-13375 -1375);
DISPLAY INVISIBLE (-13375 -1375);
FORCEPROP 2 LAST $SEC 1
J 2
(-13375 -1375);
DISPLAY 0.680851 (-13375 -1375);
PAINT MONO (-13375 -1375);
DISPLAY INVISIBLE (-13375 -1375);
FORCEPROP 2 LAST CDS_SEC 1
J 2
(-13375 -1375);
DISPLAY 1.021277 (-13375 -1375);
DISPLAY INVISIBLE (-13375 -1375);
FORCEPROP 1 LASTPIN (-13425 -1575) $PN 1
R 2
J 2
(-13413 -1489);
DISPLAY 0.808511 (-13413 -1489);
PAINT WHITE (-13413 -1489);
DISPLAY INVISIBLE (-13413 -1489);
FORCEPROP 1 LASTPIN (-13225 -1575) $PN 2
R 2
J 2
(-13263 -1489);
DISPLAY 0.808511 (-13263 -1489);
PAINT WHITE (-13263 -1489);
DISPLAY INVISIBLE (-13263 -1489);
FORCEADD Q_RES..1
(-13325 -1525);
FORCEPROP 1 LAST PART_NUMBER CS00002JB13
J 0
(-13475 -1475);
DISPLAY 0.510638 (-13475 -1475);
DISPLAY INVISIBLE (-13475 -1475);
FORCEPROP 1 LAST VALUE 0
J 2
(-13175 -1525);
DISPLAY 0.510638 (-13175 -1525);
FORCEPROP 1 LAST TOLERANCE 5%
J 0
(-13150 -1525);
DISPLAY 0.510638 (-13150 -1525);
FORCEPROP 1 LAST MATERIAL CHIP
J 0
(-13075 -1525);
DISPLAY 0.510638 (-13075 -1525);
FORCEPROP 1 LAST $LOCATION R3777
J 0
(-13550 -1525);
DISPLAY 0.638298 (-13550 -1525);
FORCEPROP 1 LASTPIN (-13425 -1525) $PN 1
J 0
(-13413 -1513);
DISPLAY 0.787234 (-13413 -1513);
PAINT MONO (-13413 -1513);
FORCEPROP 1 LASTPIN (-13225 -1525) $PN 2
J 0
(-13263 -1513);
DISPLAY 0.787234 (-13263 -1513);
PAINT MONO (-13263 -1513);
FORCEPROP 1 LAST WATTAGE 1/16W
J 2
(-13175 -1425);
DISPLAY 0.510638 (-13175 -1425);
DISPLAY INVISIBLE (-13175 -1425);
FORCEPROP 1 LAST PACK_TYPE 0402LF
J 0
(-13475 -1425);
DISPLAY 0.510638 (-13475 -1425);
DISPLAY INVISIBLE (-13475 -1425);
FORCEPROP 2 LAST CDS_LIB pure_quanta
J 0
(-13325 -1525);
DISPLAY INVISIBLE (-13325 -1525);
FORCEPROP 1 LAST PATH I19
J 0
(-13375 -1375);
DISPLAY 0.978723 (-13375 -1375);
PAINT WHITE (-13375 -1375);
DISPLAY INVISIBLE (-13375 -1375);
FORCEPROP 0 LAST CDS_LOCATION R3777
J 0
(-13375 -1425);
DISPLAY 1.021277 (-13375 -1425);
DISPLAY INVISIBLE (-13375 -1425);
FORCEPROP 0 LAST $SEC 1
J 0
(-13375 -1425);
DISPLAY 0.680851 (-13375 -1425);
PAINT MONO (-13375 -1425);
DISPLAY INVISIBLE (-13375 -1425);
FORCEPROP 0 LAST CDS_SEC 1
J 0
(-13375 -1425);
DISPLAY 1.021277 (-13375 -1425);
DISPLAY INVISIBLE (-13375 -1425);
FORCEADD Q_RES..2
(-14825 -2425);
FORCEPROP 1 LAST PART_NUMBER CS00002JB13
J 0
(-14785 -2550);
DISPLAY 0.978723 (-14785 -2550);
DISPLAY INVISIBLE (-14785 -2550);
FORCEPROP 1 LAST PACK_TYPE 0402LF
J 0
(-14785 -2600);
DISPLAY 0.978723 (-14785 -2600);
FORCEPROP 1 LAST WATTAGE 1/16W
J 0
(-14785 -2450);
DISPLAY 0.978723 (-14785 -2450);
FORCEPROP 1 LAST MATERIAL CHIP
J 0
(-14785 -2500);
DISPLAY 0.978723 (-14785 -2500);
FORCEPROP 1 LAST TOLERANCE 5%
J 0
(-14780 -2400);
DISPLAY 0.978723 (-14780 -2400);
FORCEPROP 1 LAST VALUE 0
J 0
(-14780 -2350);
DISPLAY 0.978723 (-14780 -2350);
FORCEPROP 1 LAST $LOCATION R4809
J 0
(-14780 -2300);
DISPLAY 0.978723 (-14780 -2300);
FORCEPROP 1 LASTPIN (-14825 -2325) $PN 1
J 0
(-14820 -2363);
DISPLAY 0.787234 (-14820 -2363);
PAINT MONO (-14820 -2363);
FORCEPROP 1 LASTPIN (-14825 -2525) $PN 2
J 0
(-14820 -2515);
DISPLAY 0.787234 (-14820 -2515);
PAINT MONO (-14820 -2515);
FORCEPROP 2 LAST CDS_LIB pure_quanta
J 0
(-14825 -2425);
DISPLAY INVISIBLE (-14825 -2425);
FORCEPROP 1 LAST PATH I2
J 0
(-14775 -2250);
DISPLAY 0.978723 (-14775 -2250);
PAINT WHITE (-14775 -2250);
DISPLAY INVISIBLE (-14775 -2250);
FORCEPROP 0 LAST CDS_LOCATION R4809
J 0
(-14775 -2250);
DISPLAY 1.021277 (-14775 -2250);
DISPLAY INVISIBLE (-14775 -2250);
FORCEPROP 0 LAST $SEC 1
J 0
(-14775 -2250);
DISPLAY 0.680851 (-14775 -2250);
PAINT MONO (-14775 -2250);
DISPLAY INVISIBLE (-14775 -2250);
FORCEPROP 0 LAST CDS_SEC 1
J 0
(-14775 -2250);
DISPLAY 1.021277 (-14775 -2250);
DISPLAY INVISIBLE (-14775 -2250);
FORCEADD Q_RES..1
(-13325 -1425);
FORCEPROP 1 LAST PART_NUMBER CS00002JB13
J 0
(-13475 -1375);
DISPLAY 0.510638 (-13475 -1375);
DISPLAY INVISIBLE (-13475 -1375);
FORCEPROP 1 LAST VALUE 0
J 2
(-13175 -1425);
DISPLAY 0.510638 (-13175 -1425);
FORCEPROP 1 LAST TOLERANCE 5%
J 0
(-13150 -1425);
DISPLAY 0.510638 (-13150 -1425);
FORCEPROP 1 LAST MATERIAL CHIP
J 0
(-13075 -1425);
DISPLAY 0.510638 (-13075 -1425);
FORCEPROP 1 LAST $LOCATION R1798
J 0
(-13550 -1425);
DISPLAY 0.638298 (-13550 -1425);
FORCEPROP 1 LASTPIN (-13425 -1425) $PN 1
J 0
(-13413 -1413);
DISPLAY 0.638298 (-13413 -1413);
PAINT MONO (-13413 -1413);
FORCEPROP 1 LASTPIN (-13225 -1425) $PN 2
J 0
(-13263 -1413);
DISPLAY 0.638298 (-13263 -1413);
PAINT MONO (-13263 -1413);
FORCEPROP 1 LAST PACK_TYPE 0402LF
J 0
(-13475 -1325);
DISPLAY 0.510638 (-13475 -1325);
DISPLAY INVISIBLE (-13475 -1325);
FORCEPROP 1 LAST WATTAGE 1/16W
J 2
(-13175 -1325);
DISPLAY 0.510638 (-13175 -1325);
DISPLAY INVISIBLE (-13175 -1325);
FORCEPROP 2 LAST CDS_LIB pure_quanta
J 0
(-13325 -1425);
DISPLAY INVISIBLE (-13325 -1425);
FORCEPROP 1 LAST PATH I20
J 0
(-13375 -1275);
DISPLAY 0.978723 (-13375 -1275);
PAINT WHITE (-13375 -1275);
DISPLAY INVISIBLE (-13375 -1275);
FORCEPROP 0 LAST CDS_LOCATION R1798
J 0
(-13075 -1400);
DISPLAY 1.021277 (-13075 -1400);
DISPLAY INVISIBLE (-13075 -1400);
FORCEPROP 0 LAST $SEC 1
J 0
(-13075 -1400);
DISPLAY 0.680851 (-13075 -1400);
PAINT MONO (-13075 -1400);
DISPLAY INVISIBLE (-13075 -1400);
FORCEPROP 0 LAST CDS_SEC 1
J 0
(-13075 -1400);
DISPLAY 1.021277 (-13075 -1400);
DISPLAY INVISIBLE (-13075 -1400);
FORCEADD Q_RES..1
(-13325 -1375);
FORCEPROP 1 LAST PART_NUMBER CS00002JB13
J 0
(-13475 -1325);
DISPLAY 0.510638 (-13475 -1325);
DISPLAY INVISIBLE (-13475 -1325);
FORCEPROP 1 LAST TOLERANCE 5%
J 0
(-13150 -1375);
DISPLAY 0.510638 (-13150 -1375);
FORCEPROP 1 LAST MATERIAL CHIP
J 0
(-13075 -1375);
DISPLAY 0.510638 (-13075 -1375);
FORCEPROP 1 LAST VALUE 0
J 2
(-13175 -1375);
DISPLAY 0.510638 (-13175 -1375);
FORCEPROP 1 LAST $LOCATION R3776
J 0
(-13550 -1375);
DISPLAY 0.638298 (-13550 -1375);
FORCEPROP 1 LASTPIN (-13425 -1375) $PN 1
J 0
(-13413 -1363);
DISPLAY 0.787234 (-13413 -1363);
PAINT MONO (-13413 -1363);
FORCEPROP 1 LASTPIN (-13225 -1375) $PN 2
J 0
(-13263 -1363);
DISPLAY 0.787234 (-13263 -1363);
PAINT MONO (-13263 -1363);
FORCEPROP 1 LAST PACK_TYPE 0402LF
J 0
(-13475 -1275);
DISPLAY 0.510638 (-13475 -1275);
DISPLAY INVISIBLE (-13475 -1275);
FORCEPROP 1 LAST WATTAGE 1/16W
J 2
(-13175 -1275);
DISPLAY 0.510638 (-13175 -1275);
DISPLAY INVISIBLE (-13175 -1275);
FORCEPROP 2 LAST CDS_LIB pure_quanta
J 0
(-13325 -1375);
DISPLAY INVISIBLE (-13325 -1375);
FORCEPROP 1 LAST PATH I21
J 0
(-13375 -1225);
DISPLAY 0.978723 (-13375 -1225);
PAINT WHITE (-13375 -1225);
DISPLAY INVISIBLE (-13375 -1225);
FORCEPROP 0 LAST CDS_LOCATION R3776
J 0
(-13375 -1275);
DISPLAY 1.021277 (-13375 -1275);
DISPLAY INVISIBLE (-13375 -1275);
FORCEPROP 0 LAST $SEC 1
J 0
(-13375 -1275);
DISPLAY 0.680851 (-13375 -1275);
PAINT MONO (-13375 -1275);
DISPLAY INVISIBLE (-13375 -1275);
FORCEPROP 0 LAST CDS_SEC 1
J 0
(-13375 -1275);
DISPLAY 1.021277 (-13375 -1275);
DISPLAY INVISIBLE (-13375 -1275);
FORCEADD Q_RES..1
(-13300 -675);
FORCEPROP 1 LAST PART_NUMBER CS03322FB03
J 0
(-13425 -625);
DISPLAY 0.404255 (-13425 -625);
DISPLAY INVISIBLE (-13425 -625);
FORCEPROP 1 LAST VALUE 33.2
J 2
(-13100 -675);
DISPLAY 0.510638 (-13100 -675);
FORCEPROP 1 LAST MATERIAL CHIP
J 0
(-13000 -675);
DISPLAY 0.510638 (-13000 -675);
FORCEPROP 1 LAST TOLERANCE 1%
J 0
(-13075 -675);
DISPLAY 0.510638 (-13075 -675);
FORCEPROP 1 LAST $LOCATION R2417
J 0
(-13525 -675);
DISPLAY 0.638298 (-13525 -675);
FORCEPROP 1 LASTPIN (-13400 -675) $PN 1
J 0
(-13388 -663);
DISPLAY 0.787234 (-13388 -663);
PAINT MONO (-13388 -663);
FORCEPROP 1 LASTPIN (-13200 -675) $PN 2
J 0
(-13238 -663);
DISPLAY 0.787234 (-13238 -663);
PAINT MONO (-13238 -663);
FORCEPROP 2 LAST CDS_LIB pure_quanta
J 0
(-13300 -675);
DISPLAY INVISIBLE (-13300 -675);
FORCEPROP 1 LAST PACK_TYPE 0402LF
J 0
(-13425 -575);
DISPLAY 0.404255 (-13425 -575);
DISPLAY INVISIBLE (-13425 -575);
FORCEPROP 1 LAST WATTAGE 1/16W
J 2
(-13200 -575);
DISPLAY 0.404255 (-13200 -575);
DISPLAY INVISIBLE (-13200 -575);
FORCEPROP 1 LAST PATH I22
J 0
(-13350 -525);
DISPLAY 0.978723 (-13350 -525);
PAINT WHITE (-13350 -525);
DISPLAY INVISIBLE (-13350 -525);
FORCEPROP 0 LAST CDS_LOCATION R2417
J 0
(-13525 -625);
DISPLAY 1.021277 (-13525 -625);
DISPLAY INVISIBLE (-13525 -625);
FORCEPROP 0 LAST $SEC 1
J 0
(-13525 -625);
DISPLAY 0.680851 (-13525 -625);
PAINT MONO (-13525 -625);
DISPLAY INVISIBLE (-13525 -625);
FORCEPROP 0 LAST CDS_SEC 1
J 0
(-13525 -625);
DISPLAY 1.021277 (-13525 -625);
DISPLAY INVISIBLE (-13525 -625);
FORCEADD Q_RES..1
(-13300 -725);
FORCEPROP 1 LAST PART_NUMBER CS03322FB03
J 0
(-13425 -675);
DISPLAY 0.404255 (-13425 -675);
DISPLAY INVISIBLE (-13425 -675);
FORCEPROP 1 LAST MATERIAL CHIP
J 0
(-13000 -725);
DISPLAY 0.510638 (-13000 -725);
FORCEPROP 1 LAST TOLERANCE 1%
J 0
(-13075 -725);
DISPLAY 0.510638 (-13075 -725);
FORCEPROP 1 LAST VALUE 33.2
J 2
(-13100 -725);
DISPLAY 0.510638 (-13100 -725);
FORCEPROP 1 LAST $LOCATION R2418
J 0
(-13525 -725);
DISPLAY 0.638298 (-13525 -725);
FORCEPROP 1 LASTPIN (-13400 -725) $PN 1
J 0
(-13388 -713);
DISPLAY 0.787234 (-13388 -713);
PAINT MONO (-13388 -713);
FORCEPROP 1 LASTPIN (-13200 -725) $PN 2
J 0
(-13238 -713);
DISPLAY 0.787234 (-13238 -713);
PAINT MONO (-13238 -713);
FORCEPROP 1 LAST WATTAGE 1/16W
J 2
(-13200 -625);
DISPLAY 0.404255 (-13200 -625);
DISPLAY INVISIBLE (-13200 -625);
FORCEPROP 1 LAST PACK_TYPE 0402LF
J 0
(-13425 -625);
DISPLAY 0.404255 (-13425 -625);
DISPLAY INVISIBLE (-13425 -625);
FORCEPROP 2 LAST CDS_LIB pure_quanta
J 0
(-13300 -725);
DISPLAY INVISIBLE (-13300 -725);
FORCEPROP 1 LAST PATH I23
J 0
(-13350 -575);
DISPLAY 0.978723 (-13350 -575);
PAINT WHITE (-13350 -575);
DISPLAY INVISIBLE (-13350 -575);
FORCEPROP 0 LAST CDS_LOCATION R2418
J 0
(-13525 -675);
DISPLAY 1.021277 (-13525 -675);
DISPLAY INVISIBLE (-13525 -675);
FORCEPROP 0 LAST $SEC 1
J 0
(-13525 -675);
DISPLAY 0.680851 (-13525 -675);
PAINT MONO (-13525 -675);
DISPLAY INVISIBLE (-13525 -675);
FORCEPROP 0 LAST CDS_SEC 1
J 0
(-13525 -675);
DISPLAY 1.021277 (-13525 -675);
DISPLAY INVISIBLE (-13525 -675);
FORCEADD Q_RES..1
(-13300 -625);
FORCEPROP 1 LAST PART_NUMBER CS00002JB13
J 0
(-13425 -575);
DISPLAY 0.404255 (-13425 -575);
DISPLAY INVISIBLE (-13425 -575);
FORCEPROP 1 LAST MATERIAL CHIP
J 0
(-13000 -625);
DISPLAY 0.510638 (-13000 -625);
FORCEPROP 1 LAST VALUE 0
J 2
(-13100 -625);
DISPLAY 0.510638 (-13100 -625);
FORCEPROP 1 LAST TOLERANCE 5%
J 0
(-13075 -625);
DISPLAY 0.510638 (-13075 -625);
FORCEPROP 1 LAST $LOCATION R2416
J 0
(-13525 -625);
DISPLAY 0.638298 (-13525 -625);
FORCEPROP 1 LASTPIN (-13400 -625) $PN 1
J 0
(-13388 -613);
DISPLAY 0.787234 (-13388 -613);
PAINT MONO (-13388 -613);
FORCEPROP 1 LASTPIN (-13200 -625) $PN 2
J 0
(-13238 -613);
DISPLAY 0.787234 (-13238 -613);
PAINT MONO (-13238 -613);
FORCEPROP 2 LAST CDS_LIB pure_quanta
J 0
(-13300 -625);
DISPLAY INVISIBLE (-13300 -625);
FORCEPROP 1 LAST PACK_TYPE 0402LF
J 0
(-13425 -525);
DISPLAY 0.404255 (-13425 -525);
DISPLAY INVISIBLE (-13425 -525);
FORCEPROP 1 LAST WATTAGE 1/16W
J 2
(-13200 -525);
DISPLAY 0.404255 (-13200 -525);
DISPLAY INVISIBLE (-13200 -525);
FORCEPROP 1 LAST PATH I24
J 0
(-13350 -475);
DISPLAY 0.978723 (-13350 -475);
PAINT WHITE (-13350 -475);
DISPLAY INVISIBLE (-13350 -475);
FORCEPROP 0 LAST CDS_LOCATION R2416
J 0
(-13525 -575);
DISPLAY 1.021277 (-13525 -575);
DISPLAY INVISIBLE (-13525 -575);
FORCEPROP 0 LAST $SEC 1
J 0
(-13525 -575);
DISPLAY 0.680851 (-13525 -575);
PAINT MONO (-13525 -575);
DISPLAY INVISIBLE (-13525 -575);
FORCEPROP 0 LAST CDS_SEC 1
J 0
(-13525 -575);
DISPLAY 1.021277 (-13525 -575);
DISPLAY INVISIBLE (-13525 -575);
FORCEADD Q_RES..1
(-13300 -575);
FORCEPROP 1 LAST PART_NUMBER CS00002JB13
J 0
(-13425 -525);
DISPLAY 0.404255 (-13425 -525);
DISPLAY INVISIBLE (-13425 -525);
FORCEPROP 1 LAST MATERIAL CHIP
J 0
(-13000 -575);
DISPLAY 0.510638 (-13000 -575);
FORCEPROP 1 LAST VALUE 0
J 2
(-13100 -575);
DISPLAY 0.510638 (-13100 -575);
FORCEPROP 1 LAST TOLERANCE 5%
J 0
(-13075 -575);
DISPLAY 0.510638 (-13075 -575);
FORCEPROP 1 LAST $LOCATION R2415
J 0
(-13525 -575);
DISPLAY 0.638298 (-13525 -575);
FORCEPROP 1 LASTPIN (-13400 -575) $PN 1
J 0
(-13388 -563);
DISPLAY 0.787234 (-13388 -563);
PAINT MONO (-13388 -563);
FORCEPROP 1 LASTPIN (-13200 -575) $PN 2
J 0
(-13238 -563);
DISPLAY 0.787234 (-13238 -563);
PAINT MONO (-13238 -563);
FORCEPROP 2 LAST CDS_LIB pure_quanta
J 0
(-13300 -575);
DISPLAY INVISIBLE (-13300 -575);
FORCEPROP 1 LAST PACK_TYPE 0402LF
J 0
(-13425 -475);
DISPLAY 0.404255 (-13425 -475);
DISPLAY INVISIBLE (-13425 -475);
FORCEPROP 1 LAST WATTAGE 1/16W
J 2
(-13200 -475);
DISPLAY 0.404255 (-13200 -475);
DISPLAY INVISIBLE (-13200 -475);
FORCEPROP 1 LAST PATH I25
J 0
(-13350 -425);
DISPLAY 0.978723 (-13350 -425);
PAINT WHITE (-13350 -425);
DISPLAY INVISIBLE (-13350 -425);
FORCEPROP 0 LAST CDS_LOCATION R2415
J 0
(-13525 -525);
DISPLAY 1.021277 (-13525 -525);
DISPLAY INVISIBLE (-13525 -525);
FORCEPROP 0 LAST $SEC 1
J 0
(-13525 -525);
DISPLAY 0.680851 (-13525 -525);
PAINT MONO (-13525 -525);
DISPLAY INVISIBLE (-13525 -525);
FORCEPROP 0 LAST CDS_SEC 1
J 0
(-13525 -525);
DISPLAY 1.021277 (-13525 -525);
DISPLAY INVISIBLE (-13525 -525);
FORCEADD Q_RES..1
(-13075 -1125);
FORCEPROP 1 LAST PART_NUMBER CS00002JB13
J 0
(-13225 -1175);
DISPLAY 0.510638 (-13225 -1175);
DISPLAY INVISIBLE (-13225 -1175);
FORCEPROP 1 LAST VALUE 0
J 2
(-12925 -1125);
DISPLAY 0.510638 (-12925 -1125);
FORCEPROP 1 LAST MATERIAL CHIP
J 0
(-12825 -1125);
DISPLAY 0.510638 (-12825 -1125);
FORCEPROP 1 LAST TOLERANCE 5%
J 0
(-12900 -1125);
DISPLAY 0.510638 (-12900 -1125);
FORCEPROP 1 LAST $LOCATION R1815
J 0
(-13325 -1125);
DISPLAY 0.638298 (-13325 -1125);
FORCEPROP 1 LASTPIN (-13175 -1125) $PN 1
J 0
(-13163 -1113);
DISPLAY 0.787234 (-13163 -1113);
FORCEPROP 1 LASTPIN (-12975 -1125) $PN 2
J 0
(-13013 -1113);
DISPLAY 0.787234 (-13013 -1113);
FORCEPROP 2 LAST CDS_LIB pure_quanta
J 0
(-13075 -1125);
PAINT MONO (-13075 -1125);
DISPLAY INVISIBLE (-13075 -1125);
FORCEPROP 1 LAST WATTAGE 1/16W
J 2
(-12925 -1225);
DISPLAY 0.510638 (-12925 -1225);
DISPLAY INVISIBLE (-12925 -1225);
FORCEPROP 1 LAST PACK_TYPE 0402LF
J 0
(-13225 -1225);
DISPLAY 0.510638 (-13225 -1225);
DISPLAY INVISIBLE (-13225 -1225);
FORCEPROP 1 LAST PATH I26
J 0
(-13125 -975);
DISPLAY 0.978723 (-13125 -975);
PAINT WHITE (-13125 -975);
DISPLAY INVISIBLE (-13125 -975);
FORCEPROP 2 LAST CDS_LOCATION R1815
J 0
(-13125 -925);
DISPLAY 1.021277 (-13125 -925);
DISPLAY INVISIBLE (-13125 -925);
FORCEPROP 2 LAST $SEC 1
J 0
(-13125 -925);
DISPLAY 0.680851 (-13125 -925);
PAINT MONO (-13125 -925);
DISPLAY INVISIBLE (-13125 -925);
FORCEPROP 2 LAST CDS_SEC 1
J 0
(-13125 -925);
DISPLAY 1.021277 (-13125 -925);
DISPLAY INVISIBLE (-13125 -925);
FORCEADD Q_RES..1
(-13075 -975);
FORCEPROP 1 LAST PART_NUMBER CS00002JB13
J 0
(-13225 -1025);
DISPLAY 0.510638 (-13225 -1025);
DISPLAY INVISIBLE (-13225 -1025);
FORCEPROP 1 LAST MATERIAL CHIP
J 0
(-12825 -975);
DISPLAY 0.510638 (-12825 -975);
FORCEPROP 1 LAST VALUE 0
J 2
(-12925 -975);
DISPLAY 0.510638 (-12925 -975);
FORCEPROP 1 LAST TOLERANCE 5%
J 0
(-12900 -975);
DISPLAY 0.510638 (-12900 -975);
FORCEPROP 1 LAST $LOCATION R1816
J 0
(-13325 -975);
DISPLAY 0.638298 (-13325 -975);
FORCEPROP 1 LASTPIN (-13175 -975) $PN 1
J 0
(-13163 -963);
DISPLAY 0.787234 (-13163 -963);
FORCEPROP 1 LASTPIN (-12975 -975) $PN 2
J 0
(-13013 -963);
DISPLAY 0.787234 (-13013 -963);
FORCEPROP 1 LAST WATTAGE 1/16W
J 2
(-12925 -1075);
DISPLAY 0.510638 (-12925 -1075);
DISPLAY INVISIBLE (-12925 -1075);
FORCEPROP 1 LAST PACK_TYPE 0402LF
J 0
(-13225 -1075);
DISPLAY 0.510638 (-13225 -1075);
DISPLAY INVISIBLE (-13225 -1075);
FORCEPROP 2 LAST CDS_LIB pure_quanta
J 0
(-13075 -975);
PAINT MONO (-13075 -975);
DISPLAY INVISIBLE (-13075 -975);
FORCEPROP 1 LAST PATH I27
J 0
(-13125 -825);
DISPLAY 0.978723 (-13125 -825);
PAINT WHITE (-13125 -825);
DISPLAY INVISIBLE (-13125 -825);
FORCEPROP 2 LAST CDS_LOCATION R1816
J 0
(-13125 -775);
DISPLAY 1.021277 (-13125 -775);
DISPLAY INVISIBLE (-13125 -775);
FORCEPROP 2 LAST $SEC 1
J 0
(-13125 -775);
DISPLAY 0.680851 (-13125 -775);
PAINT MONO (-13125 -775);
DISPLAY INVISIBLE (-13125 -775);
FORCEPROP 2 LAST CDS_SEC 1
J 0
(-13125 -775);
DISPLAY 1.021277 (-13125 -775);
DISPLAY INVISIBLE (-13125 -775);
FORCEADD Q_RES..1
(-13075 -925);
FORCEPROP 1 LAST PART_NUMBER CS03322FB03
J 0
(-13200 -875);
DISPLAY 0.404255 (-13200 -875);
DISPLAY INVISIBLE (-13200 -875);
FORCEPROP 1 LAST MATERIAL CHIP
J 0
(-12775 -925);
DISPLAY 0.510638 (-12775 -925);
FORCEPROP 1 LAST VALUE 33.2
J 2
(-12875 -925);
DISPLAY 0.510638 (-12875 -925);
FORCEPROP 1 LAST TOLERANCE 1%
J 0
(-12850 -925);
DISPLAY 0.510638 (-12850 -925);
FORCEPROP 1 LAST LOCATION R4087
J 0
(-13275 -925);
DISPLAY 0.510638 (-13275 -925);
FORCEPROP 1 LASTPIN (-13175 -925) $PN 1
J 0
(-13163 -913);
DISPLAY 0.787234 (-13163 -913);
PAINT MONO (-13163 -913);
FORCEPROP 1 LASTPIN (-12975 -925) $PN 2
J 0
(-13013 -913);
DISPLAY 0.787234 (-13013 -913);
PAINT MONO (-13013 -913);
FORCEPROP 2 LAST CDS_LIB pure_quanta
J 0
(-13075 -925);
DISPLAY INVISIBLE (-13075 -925);
FORCEPROP 1 LAST WATTAGE 1/16W
J 2
(-12975 -825);
DISPLAY 0.404255 (-12975 -825);
DISPLAY INVISIBLE (-12975 -825);
FORCEPROP 1 LAST PACK_TYPE 0402LF
J 0
(-13200 -825);
DISPLAY 0.404255 (-13200 -825);
DISPLAY INVISIBLE (-13200 -825);
FORCEPROP 1 LAST PATH I28
J 0
(-13125 -775);
DISPLAY 0.978723 (-13125 -775);
PAINT WHITE (-13125 -775);
DISPLAY INVISIBLE (-13125 -775);
FORCEPROP 0 LAST $SEC 1
J 0
(-12775 -900);
DISPLAY 0.680851 (-12775 -900);
PAINT MONO (-12775 -900);
DISPLAY INVISIBLE (-12775 -900);
FORCEPROP 0 LAST CDS_SEC 1
J 0
(-12775 -900);
DISPLAY 1.021277 (-12775 -900);
DISPLAY INVISIBLE (-12775 -900);
FORCEADD OFFPAGE..1
(-12450 -2175);
FORCEPROP 2 LAST $XR0 212 
J 0
(-12732 -2175);
DISPLAY 0.638298 (-12732 -2175);
PAINT MONO (-12732 -2175);
FORCEPROP 1 LAST OFFPAGE TRUE
J 0
(-12125 -2300);
DISPLAY 0.872340 (-12125 -2300);
PAINT GREEN (-12125 -2300);
DISPLAY INVISIBLE (-12125 -2300);
FORCEPROP 1 LAST COMMENT_BODY TRUE
J 0
(-12325 -2275);
DISPLAY 0.872340 (-12325 -2275);
PAINT PEACH (-12325 -2275);
DISPLAY INVISIBLE (-12325 -2275);
FORCEPROP 2 LAST CDS_LIB standard
J 0
(-12450 -2175);
DISPLAY INVISIBLE (-12450 -2175);
FORCEPROP 2 LAST PATH I29
J 0
(-12725 -2125);
DISPLAY 1.021277 (-12725 -2125);
DISPLAY INVISIBLE (-12725 -2125);
FORCEADD OFFPAGE..1
(-14575 -1575);
FORCEPROP 2 LAST $XR0 205 
J 0
(-14857 -1575);
DISPLAY 0.638298 (-14857 -1575);
PAINT MONO (-14857 -1575);
FORCEPROP 1 LAST OFFPAGE TRUE
J 0
(-14250 -1700);
DISPLAY 0.872340 (-14250 -1700);
PAINT GREEN (-14250 -1700);
DISPLAY INVISIBLE (-14250 -1700);
FORCEPROP 1 LAST COMMENT_BODY TRUE
J 0
(-14450 -1675);
DISPLAY 0.872340 (-14450 -1675);
PAINT PEACH (-14450 -1675);
DISPLAY INVISIBLE (-14450 -1675);
FORCEPROP 2 LAST CDS_LIB standard
J 0
(-14575 -1575);
DISPLAY INVISIBLE (-14575 -1575);
FORCEPROP 2 LAST PATH I3
J 0
(-14850 -1525);
DISPLAY 1.021277 (-14850 -1525);
DISPLAY INVISIBLE (-14850 -1525);
FORCEADD OFFPAGE..1
(-12450 -2225);
FORCEPROP 2 LAST $XR0 212 
J 0
(-12732 -2225);
DISPLAY 0.638298 (-12732 -2225);
PAINT MONO (-12732 -2225);
FORCEPROP 1 LAST OFFPAGE TRUE
J 0
(-12125 -2350);
DISPLAY 0.872340 (-12125 -2350);
PAINT GREEN (-12125 -2350);
DISPLAY INVISIBLE (-12125 -2350);
FORCEPROP 1 LAST COMMENT_BODY TRUE
J 0
(-12325 -2325);
DISPLAY 0.872340 (-12325 -2325);
PAINT PEACH (-12325 -2325);
DISPLAY INVISIBLE (-12325 -2325);
FORCEPROP 2 LAST CDS_LIB standard
J 0
(-12450 -2225);
DISPLAY INVISIBLE (-12450 -2225);
FORCEPROP 2 LAST PATH I30
J 0
(-12725 -2175);
DISPLAY 1.021277 (-12725 -2175);
DISPLAY INVISIBLE (-12725 -2175);
FORCEADD OFFPAGE..1
(-12450 -2075);
FORCEPROP 2 LAST $XR0 167 
J 0
(-12732 -2075);
DISPLAY 0.638298 (-12732 -2075);
PAINT MONO (-12732 -2075);
FORCEPROP 2 LAST CDS_LIB standard
J 0
(-12450 -2075);
DISPLAY INVISIBLE (-12450 -2075);
FORCEPROP 1 LAST COMMENT_BODY TRUE
J 0
(-12325 -2175);
DISPLAY 0.872340 (-12325 -2175);
PAINT PEACH (-12325 -2175);
DISPLAY INVISIBLE (-12325 -2175);
FORCEPROP 1 LAST OFFPAGE TRUE
J 0
(-12125 -2200);
DISPLAY 0.872340 (-12125 -2200);
PAINT GREEN (-12125 -2200);
DISPLAY INVISIBLE (-12125 -2200);
FORCEPROP 2 LAST PATH I31
J 0
(-12725 -2025);
DISPLAY 1.021277 (-12725 -2025);
DISPLAY INVISIBLE (-12725 -2025);
FORCEADD OFFPAGE..1
(-12450 -2025);
FORCEPROP 2 LAST $XR0 167 
J 0
(-12732 -2025);
DISPLAY 0.638298 (-12732 -2025);
PAINT MONO (-12732 -2025);
FORCEPROP 2 LAST CDS_LIB standard
J 0
(-12450 -2025);
DISPLAY INVISIBLE (-12450 -2025);
FORCEPROP 1 LAST COMMENT_BODY TRUE
J 0
(-12325 -2125);
DISPLAY 0.872340 (-12325 -2125);
PAINT PEACH (-12325 -2125);
DISPLAY INVISIBLE (-12325 -2125);
FORCEPROP 1 LAST OFFPAGE TRUE
J 0
(-12125 -2150);
DISPLAY 0.872340 (-12125 -2150);
PAINT GREEN (-12125 -2150);
DISPLAY INVISIBLE (-12125 -2150);
FORCEPROP 2 LAST PATH I32
J 0
(-12725 -1975);
DISPLAY 1.021277 (-12725 -1975);
DISPLAY INVISIBLE (-12725 -1975);
FORCEADD OFFPAGE..5
(-12450 -1775);
FORCEPROP 2 LAST $XR0 169 
J 0
(-12705 -1775);
DISPLAY 0.638298 (-12705 -1775);
PAINT MONO (-12705 -1775);
FORCEPROP 2 LAST CDS_LIB standard
J 0
(-12450 -1775);
DISPLAY INVISIBLE (-12450 -1775);
FORCEPROP 1 LAST OFFPAGE TRUE
J 0
(-12125 -1900);
DISPLAY 0.872340 (-12125 -1900);
PAINT GREEN (-12125 -1900);
DISPLAY INVISIBLE (-12125 -1900);
FORCEPROP 1 LAST COMMENT_BODY TRUE
J 0
(-12350 -1850);
DISPLAY 0.872340 (-12350 -1850);
PAINT PEACH (-12350 -1850);
DISPLAY INVISIBLE (-12350 -1850);
FORCEPROP 2 LAST PATH I33
J 0
(-12700 -1725);
DISPLAY 1.021277 (-12700 -1725);
DISPLAY INVISIBLE (-12700 -1725);
FORCEADD OFFPAGE..5
(-12450 -1725);
FORCEPROP 2 LAST $XR0 169 
J 0
(-12705 -1725);
DISPLAY 0.638298 (-12705 -1725);
PAINT MONO (-12705 -1725);
FORCEPROP 2 LAST CDS_LIB standard
J 0
(-12450 -1725);
DISPLAY INVISIBLE (-12450 -1725);
FORCEPROP 1 LAST COMMENT_BODY TRUE
J 0
(-12350 -1800);
DISPLAY 0.872340 (-12350 -1800);
PAINT PEACH (-12350 -1800);
DISPLAY INVISIBLE (-12350 -1800);
FORCEPROP 1 LAST OFFPAGE TRUE
J 0
(-12125 -1850);
DISPLAY 0.872340 (-12125 -1850);
PAINT GREEN (-12125 -1850);
DISPLAY INVISIBLE (-12125 -1850);
FORCEPROP 2 LAST PATH I34
J 0
(-12700 -1675);
DISPLAY 1.021277 (-12700 -1675);
DISPLAY INVISIBLE (-12700 -1675);
FORCEADD OFFPAGE..5
(-12450 -1625);
FORCEPROP 2 LAST $XR0 242 
J 0
(-12705 -1625);
DISPLAY 0.638298 (-12705 -1625);
PAINT MONO (-12705 -1625);
FORCEPROP 1 LAST COMMENT_BODY TRUE
J 0
(-12350 -1700);
DISPLAY 0.872340 (-12350 -1700);
PAINT PEACH (-12350 -1700);
DISPLAY INVISIBLE (-12350 -1700);
FORCEPROP 1 LAST OFFPAGE TRUE
J 0
(-12125 -1750);
DISPLAY 0.872340 (-12125 -1750);
PAINT GREEN (-12125 -1750);
DISPLAY INVISIBLE (-12125 -1750);
FORCEPROP 2 LAST CDS_LIB standard
J 0
(-12450 -1625);
DISPLAY INVISIBLE (-12450 -1625);
FORCEPROP 2 LAST PATH I35
J 0
(-12700 -1575);
DISPLAY 1.021277 (-12700 -1575);
DISPLAY INVISIBLE (-12700 -1575);
FORCEADD OFFPAGE..1
(-12450 -1325);
FORCEPROP 2 LAST $XR0 223 
J 0
(-12732 -1325);
DISPLAY 0.638298 (-12732 -1325);
PAINT MONO (-12732 -1325);
FORCEPROP 1 LAST OFFPAGE TRUE
J 0
(-12125 -1450);
DISPLAY 0.872340 (-12125 -1450);
PAINT GREEN (-12125 -1450);
DISPLAY INVISIBLE (-12125 -1450);
FORCEPROP 1 LAST COMMENT_BODY TRUE
J 0
(-12325 -1425);
DISPLAY 0.872340 (-12325 -1425);
PAINT PEACH (-12325 -1425);
DISPLAY INVISIBLE (-12325 -1425);
FORCEPROP 2 LAST CDS_LIB standard
J 0
(-12450 -1325);
DISPLAY INVISIBLE (-12450 -1325);
FORCEPROP 2 LAST PATH I36
J 0
(-12725 -1275);
DISPLAY 1.021277 (-12725 -1275);
DISPLAY INVISIBLE (-12725 -1275);
FORCEADD OFFPAGE..1
(-12450 -1275);
FORCEPROP 2 LAST $XR0 239 
J 0
(-12732 -1275);
DISPLAY 0.638298 (-12732 -1275);
PAINT MONO (-12732 -1275);
FORCEPROP 2 LAST CDS_LIB standard
J 0
(-12450 -1275);
PAINT MONO (-12450 -1275);
DISPLAY INVISIBLE (-12450 -1275);
FORCEPROP 1 LAST COMMENT_BODY TRUE
J 0
(-12325 -1375);
DISPLAY 0.872340 (-12325 -1375);
PAINT PEACH (-12325 -1375);
DISPLAY INVISIBLE (-12325 -1375);
FORCEPROP 1 LAST OFFPAGE TRUE
J 0
(-12125 -1400);
DISPLAY 0.872340 (-12125 -1400);
PAINT GREEN (-12125 -1400);
DISPLAY INVISIBLE (-12125 -1400);
FORCEPROP 2 LAST PATH I37
J 0
(-12725 -1225);
DISPLAY 1.021277 (-12725 -1225);
DISPLAY INVISIBLE (-12725 -1225);
FORCEADD OFFPAGE..5
(-12450 -1225);
FORCEPROP 2 LAST $XR0 239 
J 0
(-12705 -1225);
DISPLAY 0.638298 (-12705 -1225);
PAINT MONO (-12705 -1225);
FORCEPROP 2 LAST CDS_LIB standard
J 0
(-12450 -1225);
PAINT MONO (-12450 -1225);
DISPLAY INVISIBLE (-12450 -1225);
FORCEPROP 1 LAST COMMENT_BODY TRUE
J 0
(-12350 -1300);
DISPLAY 0.872340 (-12350 -1300);
PAINT PEACH (-12350 -1300);
DISPLAY INVISIBLE (-12350 -1300);
FORCEPROP 1 LAST OFFPAGE TRUE
J 0
(-12125 -1350);
DISPLAY 0.872340 (-12125 -1350);
PAINT GREEN (-12125 -1350);
DISPLAY INVISIBLE (-12125 -1350);
FORCEPROP 2 LAST PATH I38
J 0
(-12700 -1175);
DISPLAY 1.021277 (-12700 -1175);
DISPLAY INVISIBLE (-12700 -1175);
FORCEADD OFFPAGE..1
(-12450 -525);
FORCEPROP 2 LAST $XR0 248 
J 0
(-12732 -525);
DISPLAY 0.638298 (-12732 -525);
PAINT MONO (-12732 -525);
FORCEPROP 2 LAST CDS_LIB standard
J 0
(-12450 -525);
DISPLAY INVISIBLE (-12450 -525);
FORCEPROP 1 LAST OFFPAGE TRUE
J 0
(-12125 -650);
DISPLAY 0.872340 (-12125 -650);
PAINT GREEN (-12125 -650);
DISPLAY INVISIBLE (-12125 -650);
FORCEPROP 1 LAST COMMENT_BODY TRUE
J 0
(-12325 -625);
DISPLAY 0.872340 (-12325 -625);
PAINT PEACH (-12325 -625);
DISPLAY INVISIBLE (-12325 -625);
FORCEPROP 2 LAST PATH I39
J 0
(-12725 -475);
DISPLAY 1.021277 (-12725 -475);
DISPLAY INVISIBLE (-12725 -475);
FORCEADD OFFPAGE..1
(-14575 -1525);
FORCEPROP 2 LAST $XR0 214 
J 0
(-14857 -1525);
DISPLAY 0.638298 (-14857 -1525);
PAINT MONO (-14857 -1525);
FORCEPROP 2 LAST CDS_LIB standard
J 0
(-14575 -1525);
DISPLAY INVISIBLE (-14575 -1525);
FORCEPROP 1 LAST COMMENT_BODY TRUE
J 0
(-14450 -1625);
DISPLAY 0.872340 (-14450 -1625);
PAINT PEACH (-14450 -1625);
DISPLAY INVISIBLE (-14450 -1625);
FORCEPROP 1 LAST OFFPAGE TRUE
J 0
(-14250 -1650);
DISPLAY 0.872340 (-14250 -1650);
PAINT GREEN (-14250 -1650);
DISPLAY INVISIBLE (-14250 -1650);
FORCEPROP 2 LAST PATH I4
J 0
(-14850 -1475);
DISPLAY 1.021277 (-14850 -1475);
DISPLAY INVISIBLE (-14850 -1475);
FORCEADD UNIVERSAL_GND..1
(-11275 -2675);
FORCEPROP 3 LASTPIN (-11275 -2625) SIG_NAME GND\g
J 0
(-11265 -2615);
DISPLAY 0.659574 (-11265 -2615);
PAINT MONO (-11265 -2615);
DISPLAY INVISIBLE (-11265 -2615);
FORCEPROP 2 LAST CDS_LIB logical_power
J 0
(-11275 -2675);
DISPLAY INVISIBLE (-11275 -2675);
FORCEPROP 1 LAST HDL_POWER GND
J 1
(-11250 -2750);
DISPLAY 0.702128 (-11250 -2750);
PAINT GREEN (-11250 -2750);
DISPLAY INVISIBLE (-11250 -2750);
FORCEPROP 1 LAST PATH I40
J 0
(-11200 -2675);
DISPLAY 0.872340 (-11200 -2675);
PAINT AQUA (-11200 -2675);
DISPLAY INVISIBLE (-11200 -2675);
FORCEADD UNIVERSAL_GND..1
(-9550 -2600);
FORCEPROP 3 LASTPIN (-9550 -2550) SIG_NAME GND\g
J 0
(-9540 -2540);
DISPLAY 0.659574 (-9540 -2540);
PAINT MONO (-9540 -2540);
DISPLAY INVISIBLE (-9540 -2540);
FORCEPROP 1 LAST HDL_POWER GND
J 1
(-9525 -2675);
DISPLAY 0.702128 (-9525 -2675);
PAINT GREEN (-9525 -2675);
DISPLAY INVISIBLE (-9525 -2675);
FORCEPROP 2 LAST CDS_LIB logical_power
J 0
(-9550 -2600);
DISPLAY INVISIBLE (-9550 -2600);
FORCEPROP 1 LAST PATH I41
J 0
(-9475 -2600);
DISPLAY 0.872340 (-9475 -2600);
PAINT AQUA (-9475 -2600);
DISPLAY INVISIBLE (-9475 -2600);
FORCEADD OFFPAGE..4
(-8350 -2075);
FORCEPROP 2 LAST $XR0 167 
J 0
(-8164 -2075);
DISPLAY 0.638298 (-8164 -2075);
PAINT MONO (-8164 -2075);
FORCEPROP 2 LAST CDS_LIB standard
J 0
(-8350 -2075);
DISPLAY INVISIBLE (-8350 -2075);
FORCEPROP 1 LAST OFFPAGE TRUE
J 0
(-8025 -2200);
DISPLAY 0.872340 (-8025 -2200);
PAINT GREEN (-8025 -2200);
DISPLAY INVISIBLE (-8025 -2200);
FORCEPROP 1 LAST COMMENT_BODY TRUE
J 0
(-8375 -2175);
DISPLAY 0.872340 (-8375 -2175);
PAINT PEACH (-8375 -2175);
DISPLAY INVISIBLE (-8375 -2175);
FORCEPROP 2 LAST PATH I42
J 0
(-8150 -2025);
DISPLAY 1.021277 (-8150 -2025);
DISPLAY INVISIBLE (-8150 -2025);
FORCEADD OFFPAGE..4
(-8350 -2025);
FORCEPROP 2 LAST $XR0 167 
J 0
(-8164 -2025);
DISPLAY 0.638298 (-8164 -2025);
PAINT MONO (-8164 -2025);
FORCEPROP 1 LAST OFFPAGE TRUE
J 0
(-8025 -2150);
DISPLAY 0.872340 (-8025 -2150);
PAINT GREEN (-8025 -2150);
DISPLAY INVISIBLE (-8025 -2150);
FORCEPROP 1 LAST COMMENT_BODY TRUE
J 0
(-8375 -2125);
DISPLAY 0.872340 (-8375 -2125);
PAINT PEACH (-8375 -2125);
DISPLAY INVISIBLE (-8375 -2125);
FORCEPROP 2 LAST CDS_LIB standard
J 0
(-8350 -2025);
DISPLAY INVISIBLE (-8350 -2025);
FORCEPROP 2 LAST PATH I43
J 0
(-8150 -1975);
DISPLAY 1.021277 (-8150 -1975);
DISPLAY INVISIBLE (-8150 -1975);
FORCEADD OFFPAGE..4
(-8350 -1775);
FORCEPROP 2 LAST $XR0 169 
J 0
(-8164 -1775);
DISPLAY 0.638298 (-8164 -1775);
PAINT MONO (-8164 -1775);
FORCEPROP 2 LAST CDS_LIB standard
J 0
(-8350 -1775);
DISPLAY INVISIBLE (-8350 -1775);
FORCEPROP 1 LAST OFFPAGE TRUE
J 0
(-8025 -1900);
DISPLAY 0.872340 (-8025 -1900);
PAINT GREEN (-8025 -1900);
DISPLAY INVISIBLE (-8025 -1900);
FORCEPROP 1 LAST COMMENT_BODY TRUE
J 0
(-8375 -1875);
DISPLAY 0.872340 (-8375 -1875);
PAINT PEACH (-8375 -1875);
DISPLAY INVISIBLE (-8375 -1875);
FORCEPROP 2 LAST PATH I44
J 0
(-8150 -1725);
DISPLAY 1.021277 (-8150 -1725);
DISPLAY INVISIBLE (-8150 -1725);
FORCEADD OFFPAGE..4
(-8350 -1725);
FORCEPROP 2 LAST $XR0 169 
J 0
(-8164 -1725);
DISPLAY 0.638298 (-8164 -1725);
PAINT MONO (-8164 -1725);
FORCEPROP 2 LAST CDS_LIB standard
J 0
(-8350 -1725);
DISPLAY INVISIBLE (-8350 -1725);
FORCEPROP 1 LAST COMMENT_BODY TRUE
J 0
(-8375 -1825);
DISPLAY 0.872340 (-8375 -1825);
PAINT PEACH (-8375 -1825);
DISPLAY INVISIBLE (-8375 -1825);
FORCEPROP 1 LAST OFFPAGE TRUE
J 0
(-8025 -1850);
DISPLAY 0.872340 (-8025 -1850);
PAINT GREEN (-8025 -1850);
DISPLAY INVISIBLE (-8025 -1850);
FORCEPROP 2 LAST PATH I45
J 0
(-8150 -1675);
DISPLAY 1.021277 (-8150 -1675);
DISPLAY INVISIBLE (-8150 -1675);
FORCEADD OFFPAGE..3
(-8350 -1625);
FORCEPROP 2 LAST $XR0 196 
J 0
(-8136 -1625);
DISPLAY 0.638298 (-8136 -1625);
PAINT MONO (-8136 -1625);
FORCEPROP 1 LAST OFFPAGE TRUE
J 0
(-8025 -1750);
DISPLAY 0.872340 (-8025 -1750);
PAINT GREEN (-8025 -1750);
DISPLAY INVISIBLE (-8025 -1750);
FORCEPROP 1 LAST COMMENT_BODY TRUE
J 0
(-8400 -1725);
DISPLAY 0.872340 (-8400 -1725);
PAINT PEACH (-8400 -1725);
DISPLAY INVISIBLE (-8400 -1725);
FORCEPROP 2 LAST CDS_LIB standard
J 0
(-8350 -1625);
PAINT MONO (-8350 -1625);
DISPLAY INVISIBLE (-8350 -1625);
FORCEPROP 2 LAST PATH I46
J 0
(-8125 -1575);
DISPLAY 1.021277 (-8125 -1575);
DISPLAY INVISIBLE (-8125 -1575);
FORCEADD OFFPAGE..3
(-8350 -1575);
FORCEPROP 2 LAST $XR0 196 
J 0
(-8136 -1575);
DISPLAY 0.638298 (-8136 -1575);
PAINT MONO (-8136 -1575);
FORCEPROP 1 LAST OFFPAGE TRUE
J 0
(-8025 -1700);
DISPLAY 0.872340 (-8025 -1700);
PAINT GREEN (-8025 -1700);
DISPLAY INVISIBLE (-8025 -1700);
FORCEPROP 1 LAST COMMENT_BODY TRUE
J 0
(-8400 -1675);
DISPLAY 0.872340 (-8400 -1675);
PAINT PEACH (-8400 -1675);
DISPLAY INVISIBLE (-8400 -1675);
FORCEPROP 2 LAST CDS_LIB standard
J 0
(-8350 -1575);
PAINT MONO (-8350 -1575);
DISPLAY INVISIBLE (-8350 -1575);
FORCEPROP 2 LAST PATH I47
J 0
(-8125 -1525);
DISPLAY 1.021277 (-8125 -1525);
DISPLAY INVISIBLE (-8125 -1525);
FORCEADD Q_RES..1
(-7875 -2225);
FORCEPROP 1 LAST PART_NUMBER CS00002JB13
J 0
(-8050 -2425);
DISPLAY 0.638298 (-8050 -2425);
DISPLAY INVISIBLE (-8050 -2425);
FORCEPROP 1 LAST MATERIAL EMPTY
J 0
(-7625 -2225);
DISPLAY 0.638298 (-7625 -2225);
PAINT RED (-7625 -2225);
FORCEPROP 1 LAST VALUE 0
J 2
(-7725 -2225);
DISPLAY 0.638298 (-7725 -2225);
FORCEPROP 1 LAST $LOCATION R3302
J 0
(-8100 -2225);
DISPLAY 0.638298 (-8100 -2225);
FORCEPROP 1 LASTPIN (-7975 -2225) $PN 1
J 0
(-7963 -2213);
DISPLAY 0.787234 (-7963 -2213);
PAINT MONO (-7963 -2213);
FORCEPROP 1 LASTPIN (-7775 -2225) $PN 2
J 0
(-7813 -2213);
DISPLAY 0.787234 (-7813 -2213);
PAINT MONO (-7813 -2213);
FORCEPROP 2 LAST CDS_LIB pure_quanta
J 0
(-7875 -2225);
DISPLAY INVISIBLE (-7875 -2225);
FORCEPROP 1 LAST PACK_TYPE 0402LF
J 0
(-8050 -2375);
DISPLAY 0.638298 (-8050 -2375);
DISPLAY INVISIBLE (-8050 -2375);
FORCEPROP 1 LAST TOLERANCE 5%
J 0
(-7700 -2225);
DISPLAY 0.638298 (-7700 -2225);
DISPLAY INVISIBLE (-7700 -2225);
FORCEPROP 1 LAST WATTAGE 1/16W
J 2
(-7675 -2375);
DISPLAY 0.638298 (-7675 -2375);
DISPLAY INVISIBLE (-7675 -2375);
FORCEPROP 1 LAST PATH I48
J 0
(-7925 -2075);
DISPLAY 0.978723 (-7925 -2075);
PAINT WHITE (-7925 -2075);
DISPLAY INVISIBLE (-7925 -2075);
FORCEPROP 0 LAST CDS_LOCATION R3302
J 0
(-7625 -2175);
DISPLAY 1.021277 (-7625 -2175);
DISPLAY INVISIBLE (-7625 -2175);
FORCEPROP 0 LAST $SEC 1
J 0
(-7625 -2175);
DISPLAY 0.680851 (-7625 -2175);
PAINT MONO (-7625 -2175);
DISPLAY INVISIBLE (-7625 -2175);
FORCEPROP 0 LAST CDS_SEC 1
J 0
(-7625 -2175);
DISPLAY 1.021277 (-7625 -2175);
DISPLAY INVISIBLE (-7625 -2175);
FORCEADD Q_RES..1
(-7875 -2175);
FORCEPROP 1 LAST PART_NUMBER CS00002JB13
J 0
(-8050 -2350);
DISPLAY 0.638298 (-8050 -2350);
DISPLAY INVISIBLE (-8050 -2350);
FORCEPROP 1 LAST WATTAGE 1/16W
J 2
(-7675 -2300);
DISPLAY 0.638298 (-7675 -2300);
FORCEPROP 1 LAST TOLERANCE 5%
J 0
(-7700 -2175);
DISPLAY 0.638298 (-7700 -2175);
FORCEPROP 1 LAST VALUE 0
J 2
(-7725 -2175);
DISPLAY 0.638298 (-7725 -2175);
FORCEPROP 1 LAST PACK_TYPE 0402LF
J 0
(-8050 -2300);
DISPLAY 0.638298 (-8050 -2300);
FORCEPROP 1 LAST MATERIAL EMPTY
J 0
(-7625 -2175);
DISPLAY 0.638298 (-7625 -2175);
PAINT RED (-7625 -2175);
FORCEPROP 1 LAST $LOCATION R3254
J 0
(-8100 -2175);
DISPLAY 0.638298 (-8100 -2175);
FORCEPROP 1 LASTPIN (-7975 -2175) $PN 1
J 0
(-7963 -2163);
DISPLAY 0.787234 (-7963 -2163);
PAINT MONO (-7963 -2163);
FORCEPROP 1 LASTPIN (-7775 -2175) $PN 2
J 0
(-7813 -2163);
DISPLAY 0.787234 (-7813 -2163);
PAINT MONO (-7813 -2163);
FORCEPROP 2 LAST CDS_LIB pure_quanta
J 0
(-7875 -2175);
DISPLAY INVISIBLE (-7875 -2175);
FORCEPROP 1 LAST PATH I49
J 0
(-7925 -2025);
DISPLAY 0.978723 (-7925 -2025);
PAINT WHITE (-7925 -2025);
DISPLAY INVISIBLE (-7925 -2025);
FORCEPROP 0 LAST CDS_LOCATION R3254
J 0
(-7625 -2000);
DISPLAY 1.021277 (-7625 -2000);
DISPLAY INVISIBLE (-7625 -2000);
FORCEPROP 0 LAST $SEC 1
J 0
(-7625 -2000);
DISPLAY 0.680851 (-7625 -2000);
PAINT MONO (-7625 -2000);
DISPLAY INVISIBLE (-7625 -2000);
FORCEPROP 0 LAST CDS_SEC 1
J 0
(-7625 -2000);
DISPLAY 1.021277 (-7625 -2000);
DISPLAY INVISIBLE (-7625 -2000);
FORCEADD OFFPAGE..2
(-13925 -2225);
FORCEPROP 2 LAST $XR0 240 
J 0
(-13736 -2225);
DISPLAY 0.638298 (-13736 -2225);
PAINT MONO (-13736 -2225);
FORCEPROP 1 LAST COMMENT_BODY TRUE
J 0
(-13970 -2320);
DISPLAY 0.872340 (-13970 -2320);
PAINT GREEN (-13970 -2320);
DISPLAY INVISIBLE (-13970 -2320);
FORCEPROP 1 LAST OFFPAGE TRUE
J 0
(-13600 -2350);
DISPLAY 0.872340 (-13600 -2350);
DISPLAY INVISIBLE (-13600 -2350);
FORCEPROP 2 LAST CDS_LIB standard
J 0
(-13925 -2225);
PAINT MONO (-13925 -2225);
DISPLAY INVISIBLE (-13925 -2225);
FORCEPROP 2 LAST PATH I5
J 0
(-13725 -2175);
DISPLAY 1.021277 (-13725 -2175);
DISPLAY INVISIBLE (-13725 -2175);
FORCEADD OFFPAGE..3
(-8350 -1425);
FORCEPROP 2 LAST $XR0 180 
J 0
(-8136 -1425);
DISPLAY 0.638298 (-8136 -1425);
PAINT MONO (-8136 -1425);
FORCEPROP 2 LAST CDS_LIB standard
J 0
(-8350 -1425);
PAINT MONO (-8350 -1425);
DISPLAY INVISIBLE (-8350 -1425);
FORCEPROP 1 LAST OFFPAGE TRUE
J 0
(-8025 -1550);
DISPLAY 0.872340 (-8025 -1550);
PAINT GREEN (-8025 -1550);
DISPLAY INVISIBLE (-8025 -1550);
FORCEPROP 1 LAST COMMENT_BODY TRUE
J 0
(-8400 -1525);
DISPLAY 0.872340 (-8400 -1525);
PAINT PEACH (-8400 -1525);
DISPLAY INVISIBLE (-8400 -1525);
FORCEPROP 2 LAST PATH I50
J 0
(-8125 -1375);
DISPLAY 1.021277 (-8125 -1375);
DISPLAY INVISIBLE (-8125 -1375);
FORCEADD OFFPAGE..3
(-8350 -1475);
FORCEPROP 2 LAST $XR0 180 
J 0
(-8136 -1475);
DISPLAY 0.638298 (-8136 -1475);
PAINT MONO (-8136 -1475);
FORCEPROP 2 LAST CDS_LIB standard
J 0
(-8350 -1475);
PAINT MONO (-8350 -1475);
DISPLAY INVISIBLE (-8350 -1475);
FORCEPROP 1 LAST OFFPAGE TRUE
J 0
(-8025 -1600);
DISPLAY 0.872340 (-8025 -1600);
PAINT GREEN (-8025 -1600);
DISPLAY INVISIBLE (-8025 -1600);
FORCEPROP 1 LAST COMMENT_BODY TRUE
J 0
(-8400 -1575);
DISPLAY 0.872340 (-8400 -1575);
PAINT PEACH (-8400 -1575);
DISPLAY INVISIBLE (-8400 -1575);
FORCEPROP 2 LAST PATH I51
J 0
(-8125 -1425);
DISPLAY 1.021277 (-8125 -1425);
DISPLAY INVISIBLE (-8125 -1425);
FORCEADD OFFPAGE..3
(-8350 -1325);
FORCEPROP 2 LAST $XR0 152 
J 0
(-8136 -1325);
DISPLAY 0.638298 (-8136 -1325);
PAINT MONO (-8136 -1325);
FORCEPROP 2 LAST CDS_LIB standard
J 0
(-8350 -1325);
PAINT MONO (-8350 -1325);
DISPLAY INVISIBLE (-8350 -1325);
FORCEPROP 1 LAST OFFPAGE TRUE
J 0
(-8025 -1450);
DISPLAY 0.872340 (-8025 -1450);
PAINT GREEN (-8025 -1450);
DISPLAY INVISIBLE (-8025 -1450);
FORCEPROP 1 LAST COMMENT_BODY TRUE
J 0
(-8400 -1425);
DISPLAY 0.872340 (-8400 -1425);
PAINT PEACH (-8400 -1425);
DISPLAY INVISIBLE (-8400 -1425);
FORCEPROP 2 LAST PATH I52
J 0
(-8125 -1275);
DISPLAY 1.021277 (-8125 -1275);
DISPLAY INVISIBLE (-8125 -1275);
FORCEADD OFFPAGE..3
(-8350 -1275);
FORCEPROP 2 LAST $XR0 152 
J 0
(-8136 -1275);
DISPLAY 0.638298 (-8136 -1275);
PAINT MONO (-8136 -1275);
FORCEPROP 2 LAST CDS_LIB standard
J 0
(-8350 -1275);
PAINT MONO (-8350 -1275);
DISPLAY INVISIBLE (-8350 -1275);
FORCEPROP 1 LAST OFFPAGE TRUE
J 0
(-8025 -1400);
DISPLAY 0.872340 (-8025 -1400);
PAINT GREEN (-8025 -1400);
DISPLAY INVISIBLE (-8025 -1400);
FORCEPROP 1 LAST COMMENT_BODY TRUE
J 0
(-8400 -1375);
DISPLAY 0.872340 (-8400 -1375);
PAINT PEACH (-8400 -1375);
DISPLAY INVISIBLE (-8400 -1375);
FORCEPROP 2 LAST PATH I53
J 0
(-8125 -1225);
DISPLAY 1.021277 (-8125 -1225);
DISPLAY INVISIBLE (-8125 -1225);
FORCEADD OFFPAGE..4
(-8350 -675);
FORCEPROP 2 LAST $XR0 222 
J 0
(-8164 -675);
DISPLAY 0.638298 (-8164 -675);
PAINT MONO (-8164 -675);
FORCEPROP 1 LAST COMMENT_BODY TRUE
J 0
(-8375 -775);
DISPLAY 0.872340 (-8375 -775);
PAINT PEACH (-8375 -775);
DISPLAY INVISIBLE (-8375 -775);
FORCEPROP 1 LAST OFFPAGE TRUE
J 0
(-8025 -800);
DISPLAY 0.872340 (-8025 -800);
PAINT GREEN (-8025 -800);
DISPLAY INVISIBLE (-8025 -800);
FORCEPROP 2 LAST CDS_LIB standard
J 0
(-8350 -675);
PAINT MONO (-8350 -675);
DISPLAY INVISIBLE (-8350 -675);
FORCEPROP 2 LAST PATH I54
J 0
(-8150 -625);
DISPLAY 1.021277 (-8150 -625);
DISPLAY INVISIBLE (-8150 -625);
FORCEADD OFFPAGE..2
(-8350 -625);
FORCEPROP 2 LAST $XR0 222 
J 0
(-8161 -625);
DISPLAY 0.638298 (-8161 -625);
PAINT MONO (-8161 -625);
FORCEPROP 1 LAST COMMENT_BODY TRUE
J 0
(-8395 -720);
DISPLAY 0.872340 (-8395 -720);
PAINT PEACH (-8395 -720);
DISPLAY INVISIBLE (-8395 -720);
FORCEPROP 1 LAST OFFPAGE TRUE
J 0
(-8025 -750);
DISPLAY 0.872340 (-8025 -750);
PAINT GREEN (-8025 -750);
DISPLAY INVISIBLE (-8025 -750);
FORCEPROP 2 LAST CDS_LIB standard
J 0
(-8350 -625);
PAINT MONO (-8350 -625);
DISPLAY INVISIBLE (-8350 -625);
FORCEPROP 2 LAST PATH I55
J 0
(-8150 -575);
DISPLAY 1.021277 (-8150 -575);
DISPLAY INVISIBLE (-8150 -575);
FORCEADD OFFPAGE..2
(-8350 -525);
FORCEPROP 2 LAST $XR0 222 
J 0
(-8161 -525);
DISPLAY 0.638298 (-8161 -525);
PAINT MONO (-8161 -525);
FORCEPROP 1 LAST OFFPAGE TRUE
J 0
(-8025 -650);
DISPLAY 0.872340 (-8025 -650);
PAINT GREEN (-8025 -650);
DISPLAY INVISIBLE (-8025 -650);
FORCEPROP 1 LAST COMMENT_BODY TRUE
J 0
(-8395 -620);
DISPLAY 0.872340 (-8395 -620);
PAINT PEACH (-8395 -620);
DISPLAY INVISIBLE (-8395 -620);
FORCEPROP 2 LAST CDS_LIB standard
J 0
(-8350 -525);
PAINT MONO (-8350 -525);
DISPLAY INVISIBLE (-8350 -525);
FORCEPROP 2 LAST PATH I56
J 0
(-8150 -475);
DISPLAY 1.021277 (-8150 -475);
DISPLAY INVISIBLE (-8150 -475);
FORCEADD Q_RES..1
(-7800 -775);
FORCEPROP 1 LAST PART_NUMBER CS00002JB13
J 0
(-7925 -700);
DISPLAY 0.638298 (-7925 -700);
DISPLAY INVISIBLE (-7925 -700);
FORCEPROP 1 LAST MATERIAL CHIP
J 0
(-7550 -775);
DISPLAY 0.638298 (-7550 -775);
FORCEPROP 1 LAST VALUE 0
J 2
(-7650 -775);
DISPLAY 0.638298 (-7650 -775);
FORCEPROP 1 LAST WATTAGE 1/16W
J 2
(-7825 -825);
DISPLAY 0.638298 (-7825 -825);
FORCEPROP 1 LAST $LOCATION R4720
J 0
(-8025 -775);
DISPLAY 0.638298 (-8025 -775);
FORCEPROP 1 LASTPIN (-7900 -775) $PN 1
J 0
(-7888 -763);
DISPLAY 0.787234 (-7888 -763);
PAINT MONO (-7888 -763);
FORCEPROP 1 LASTPIN (-7700 -775) $PN 2
J 0
(-7738 -763);
DISPLAY 0.787234 (-7738 -763);
PAINT MONO (-7738 -763);
FORCEPROP 2 LAST CDS_LIB pure_quanta
J 0
(-7800 -775);
DISPLAY INVISIBLE (-7800 -775);
FORCEPROP 1 LAST PACK_TYPE 0402LF
J 0
(-7925 -650);
DISPLAY 0.638298 (-7925 -650);
DISPLAY INVISIBLE (-7925 -650);
FORCEPROP 1 LAST TOLERANCE 5%
J 0
(-7625 -775);
DISPLAY 0.638298 (-7625 -775);
DISPLAY INVISIBLE (-7625 -775);
FORCEPROP 1 LAST PATH I57
J 0
(-7850 -625);
DISPLAY 0.978723 (-7850 -625);
PAINT WHITE (-7850 -625);
DISPLAY INVISIBLE (-7850 -625);
FORCEPROP 0 LAST CDS_LOCATION R4720
J 0
(-7550 -725);
DISPLAY 1.021277 (-7550 -725);
DISPLAY INVISIBLE (-7550 -725);
FORCEPROP 0 LAST $SEC 1
J 0
(-7550 -725);
DISPLAY 0.680851 (-7550 -725);
PAINT MONO (-7550 -725);
DISPLAY INVISIBLE (-7550 -725);
FORCEPROP 0 LAST CDS_SEC 1
J 0
(-7550 -725);
DISPLAY 1.021277 (-7550 -725);
DISPLAY INVISIBLE (-7550 -725);
FORCEADD Q_RES..1
(-7800 -725);
FORCEPROP 1 LAST PART_NUMBER CS00002JB13
J 0
(-7925 -650);
DISPLAY 0.638298 (-7925 -650);
DISPLAY INVISIBLE (-7925 -650);
FORCEPROP 1 LAST MATERIAL CHIP
J 0
(-7550 -725);
DISPLAY 0.638298 (-7550 -725);
FORCEPROP 1 LAST TOLERANCE 5%
J 0
(-7625 -725);
DISPLAY 0.638298 (-7625 -725);
FORCEPROP 1 LAST VALUE 0
J 2
(-7650 -725);
DISPLAY 0.638298 (-7650 -725);
FORCEPROP 1 LAST PACK_TYPE 0402LF
J 0
(-7925 -600);
DISPLAY 0.638298 (-7925 -600);
FORCEPROP 1 LAST WATTAGE 1/16W
J 2
(-7550 -600);
DISPLAY 0.638298 (-7550 -600);
FORCEPROP 1 LAST $LOCATION R2994
J 0
(-8025 -725);
DISPLAY 0.638298 (-8025 -725);
FORCEPROP 1 LASTPIN (-7900 -725) $PN 1
J 0
(-7910 -715);
DISPLAY 0.787234 (-7910 -715);
PAINT MONO (-7910 -715);
FORCEPROP 1 LASTPIN (-7700 -725) $PN 2
J 0
(-7738 -713);
DISPLAY 0.787234 (-7738 -713);
PAINT MONO (-7738 -713);
FORCEPROP 2 LAST CDS_LIB pure_quanta
J 0
(-7800 -725);
DISPLAY INVISIBLE (-7800 -725);
FORCEPROP 1 LAST PATH I58
J 0
(-7850 -575);
DISPLAY 0.978723 (-7850 -575);
PAINT WHITE (-7850 -575);
DISPLAY INVISIBLE (-7850 -575);
FORCEPROP 0 LAST CDS_LOCATION R2994
J 0
(-7550 -550);
DISPLAY 1.021277 (-7550 -550);
DISPLAY INVISIBLE (-7550 -550);
FORCEPROP 0 LAST $SEC 1
J 0
(-7550 -550);
DISPLAY 0.680851 (-7550 -550);
PAINT MONO (-7550 -550);
DISPLAY INVISIBLE (-7550 -550);
FORCEPROP 0 LAST CDS_SEC 1
J 0
(-7550 -550);
DISPLAY 1.021277 (-7550 -550);
DISPLAY INVISIBLE (-7550 -550);
FORCEADD OFFPAGE..4
(-6750 -2225);
FORCEPROP 2 LAST $XR0 185 
J 0
(-6564 -2225);
DISPLAY 0.638298 (-6564 -2225);
PAINT MONO (-6564 -2225);
FORCEPROP 2 LAST $XR1 198 
J 0
(-6444 -2225);
DISPLAY 0.638298 (-6444 -2225);
PAINT MONO (-6444 -2225);
FORCEPROP 2 LAST $XR2 214 
J 0
(-6324 -2225);
DISPLAY 0.638298 (-6324 -2225);
PAINT MONO (-6324 -2225);
FORCEPROP 1 LAST COMMENT_BODY TRUE
J 0
(-6775 -2325);
DISPLAY 0.872340 (-6775 -2325);
PAINT PEACH (-6775 -2325);
DISPLAY INVISIBLE (-6775 -2325);
FORCEPROP 1 LAST OFFPAGE TRUE
J 0
(-6425 -2350);
DISPLAY 0.872340 (-6425 -2350);
PAINT GREEN (-6425 -2350);
DISPLAY INVISIBLE (-6425 -2350);
FORCEPROP 2 LAST CDS_LIB standard
J 0
(-6750 -2225);
DISPLAY INVISIBLE (-6750 -2225);
FORCEPROP 2 LAST PATH I59
J 0
(-6300 -2175);
DISPLAY 1.021277 (-6300 -2175);
DISPLAY INVISIBLE (-6300 -2175);
FORCEADD OFFPAGE..5
(-14575 -1425);
FORCEPROP 2 LAST $XR0 215 
J 0
(-14830 -1425);
DISPLAY 0.638298 (-14830 -1425);
PAINT MONO (-14830 -1425);
FORCEPROP 2 LAST $XR1 220 
J 0
(-14950 -1425);
DISPLAY 0.638298 (-14950 -1425);
PAINT MONO (-14950 -1425);
FORCEPROP 1 LAST OFFPAGE TRUE
J 0
(-14250 -1550);
DISPLAY 0.872340 (-14250 -1550);
PAINT GREEN (-14250 -1550);
DISPLAY INVISIBLE (-14250 -1550);
FORCEPROP 1 LAST COMMENT_BODY TRUE
J 0
(-14475 -1500);
DISPLAY 0.872340 (-14475 -1500);
PAINT PEACH (-14475 -1500);
DISPLAY INVISIBLE (-14475 -1500);
FORCEPROP 2 LAST CDS_LIB standard
J 0
(-14575 -1425);
DISPLAY INVISIBLE (-14575 -1425);
FORCEPROP 2 LAST PATH I6
J 0
(-14825 -1375);
DISPLAY 1.021277 (-14825 -1375);
DISPLAY INVISIBLE (-14825 -1375);
FORCEADD OFFPAGE..4
(-6750 -2175);
FORCEPROP 2 LAST $XR0 190 
J 0
(-6564 -2175);
DISPLAY 0.638298 (-6564 -2175);
PAINT MONO (-6564 -2175);
FORCEPROP 2 LAST $XR1 214 
J 0
(-6444 -2175);
DISPLAY 0.638298 (-6444 -2175);
PAINT MONO (-6444 -2175);
FORCEPROP 2 LAST CDS_LIB standard
J 0
(-6750 -2175);
DISPLAY INVISIBLE (-6750 -2175);
FORCEPROP 1 LAST OFFPAGE TRUE
J 0
(-6425 -2300);
DISPLAY 0.872340 (-6425 -2300);
PAINT GREEN (-6425 -2300);
DISPLAY INVISIBLE (-6425 -2300);
FORCEPROP 1 LAST COMMENT_BODY TRUE
J 0
(-6775 -2275);
DISPLAY 0.872340 (-6775 -2275);
PAINT PEACH (-6775 -2275);
DISPLAY INVISIBLE (-6775 -2275);
FORCEPROP 2 LAST PATH I60
J 0
(-6425 -2125);
DISPLAY 1.021277 (-6425 -2125);
DISPLAY INVISIBLE (-6425 -2125);
FORCEADD OFFPAGE..2
(-6725 -775);
FORCEPROP 2 LAST $XR0 224 
J 0
(-6536 -775);
DISPLAY 0.638298 (-6536 -775);
PAINT MONO (-6536 -775);
FORCEPROP 2 LAST $XR1 245 
J 0
(-6416 -775);
DISPLAY 0.638298 (-6416 -775);
PAINT MONO (-6416 -775);
FORCEPROP 2 LAST CDS_LIB standard
J 0
(-6725 -775);
DISPLAY INVISIBLE (-6725 -775);
FORCEPROP 1 LAST OFFPAGE TRUE
J 0
(-6400 -900);
DISPLAY 0.872340 (-6400 -900);
PAINT GREEN (-6400 -900);
DISPLAY INVISIBLE (-6400 -900);
FORCEPROP 1 LAST COMMENT_BODY TRUE
J 0
(-6770 -870);
DISPLAY 0.872340 (-6770 -870);
PAINT PEACH (-6770 -870);
DISPLAY INVISIBLE (-6770 -870);
FORCEPROP 2 LAST PATH I61
J 0
(-6400 -725);
DISPLAY 1.021277 (-6400 -725);
DISPLAY INVISIBLE (-6400 -725);
FORCEADD OFFPAGE..4
(-6725 -725);
FORCEPROP 2 LAST $XR0 185 
J 0
(-6539 -725);
DISPLAY 0.638298 (-6539 -725);
PAINT MONO (-6539 -725);
FORCEPROP 2 LAST CDS_LIB standard
J 0
(-6725 -725);
DISPLAY INVISIBLE (-6725 -725);
FORCEPROP 1 LAST COMMENT_BODY TRUE
J 0
(-6750 -825);
DISPLAY 0.872340 (-6750 -825);
PAINT PEACH (-6750 -825);
DISPLAY INVISIBLE (-6750 -825);
FORCEPROP 1 LAST OFFPAGE TRUE
J 0
(-6400 -850);
DISPLAY 0.872340 (-6400 -850);
PAINT GREEN (-6400 -850);
DISPLAY INVISIBLE (-6400 -850);
FORCEPROP 2 LAST PATH I62
J 0
(-6525 -675);
DISPLAY 1.021277 (-6525 -675);
DISPLAY INVISIBLE (-6525 -675);
FORCEADD OFFPAGE..6
(-14575 -275);
FORCEPROP 2 LAST $XR0 241 
J 0
(-14855 -275);
DISPLAY 0.638298 (-14855 -275);
PAINT MONO (-14855 -275);
FORCEPROP 2 LAST $XR1 234 
J 0
(-14975 -275);
DISPLAY 0.638298 (-14975 -275);
PAINT MONO (-14975 -275);
FORCEPROP 2 LAST CDS_LIB standard
J 0
(-14575 -275);
DISPLAY INVISIBLE (-14575 -275);
FORCEPROP 1 LAST OFFPAGE TRUE
J 0
(-14250 -400);
DISPLAY 0.872340 (-14250 -400);
PAINT GREEN (-14250 -400);
DISPLAY INVISIBLE (-14250 -400);
FORCEPROP 1 LAST COMMENT_BODY TRUE
J 0
(-14475 -350);
DISPLAY 0.872340 (-14475 -350);
PAINT PEACH (-14475 -350);
DISPLAY INVISIBLE (-14475 -350);
FORCEPROP 2 LAST PATH I63
J 0
(-14850 -225);
DISPLAY 1.021277 (-14850 -225);
DISPLAY INVISIBLE (-14850 -225);
FORCEADD OFFPAGE..6
(-14575 -225);
FORCEPROP 2 LAST $XR0 234 
J 0
(-14855 -225);
DISPLAY 0.638298 (-14855 -225);
PAINT MONO (-14855 -225);
FORCEPROP 2 LAST $XR1 241 
J 0
(-14975 -225);
DISPLAY 0.638298 (-14975 -225);
PAINT MONO (-14975 -225);
FORCEPROP 2 LAST CDS_LIB standard
J 0
(-14575 -225);
DISPLAY INVISIBLE (-14575 -225);
FORCEPROP 1 LAST OFFPAGE TRUE
J 0
(-14250 -350);
DISPLAY 0.872340 (-14250 -350);
PAINT GREEN (-14250 -350);
DISPLAY INVISIBLE (-14250 -350);
FORCEPROP 1 LAST COMMENT_BODY TRUE
J 0
(-14475 -300);
DISPLAY 0.872340 (-14475 -300);
PAINT PEACH (-14475 -300);
DISPLAY INVISIBLE (-14475 -300);
FORCEPROP 2 LAST PATH I64
J 0
(-14850 -175);
DISPLAY 1.021277 (-14850 -175);
DISPLAY INVISIBLE (-14850 -175);
FORCEADD OFFPAGE..6
(-14575 175);
FORCEPROP 2 LAST $XR0 241 
J 0
(-14855 175);
DISPLAY 0.638298 (-14855 175);
PAINT MONO (-14855 175);
FORCEPROP 2 LAST CDS_LIB standard
J 0
(-14575 175);
DISPLAY INVISIBLE (-14575 175);
FORCEPROP 1 LAST COMMENT_BODY TRUE
J 0
(-14475 100);
DISPLAY 0.872340 (-14475 100);
PAINT PEACH (-14475 100);
DISPLAY INVISIBLE (-14475 100);
FORCEPROP 1 LAST OFFPAGE TRUE
J 0
(-14250 50);
DISPLAY 0.872340 (-14250 50);
PAINT GREEN (-14250 50);
DISPLAY INVISIBLE (-14250 50);
FORCEPROP 2 LAST PATH I65
J 0
(-14850 225);
DISPLAY 1.021277 (-14850 225);
DISPLAY INVISIBLE (-14850 225);
FORCEADD OFFPAGE..6
(-14575 125);
FORCEPROP 2 LAST $XR0 241 
J 0
(-14855 125);
DISPLAY 0.638298 (-14855 125);
PAINT MONO (-14855 125);
FORCEPROP 2 LAST CDS_LIB standard
J 0
(-14575 125);
DISPLAY INVISIBLE (-14575 125);
FORCEPROP 1 LAST COMMENT_BODY TRUE
J 0
(-14475 50);
DISPLAY 0.872340 (-14475 50);
PAINT PEACH (-14475 50);
DISPLAY INVISIBLE (-14475 50);
FORCEPROP 1 LAST OFFPAGE TRUE
J 0
(-14250 0);
DISPLAY 0.872340 (-14250 0);
PAINT GREEN (-14250 0);
DISPLAY INVISIBLE (-14250 0);
FORCEPROP 2 LAST PATH I66
J 0
(-14850 175);
DISPLAY 1.021277 (-14850 175);
DISPLAY INVISIBLE (-14850 175);
FORCEADD OFFPAGE..6
(-14575 25);
FORCEPROP 2 LAST $XR0 241 
J 0
(-14855 25);
DISPLAY 0.638298 (-14855 25);
PAINT MONO (-14855 25);
FORCEPROP 2 LAST CDS_LIB standard
J 0
(-14575 25);
PAINT MONO (-14575 25);
DISPLAY INVISIBLE (-14575 25);
FORCEPROP 1 LAST OFFPAGE TRUE
J 0
(-14250 -100);
DISPLAY 0.872340 (-14250 -100);
PAINT GREEN (-14250 -100);
DISPLAY INVISIBLE (-14250 -100);
FORCEPROP 1 LAST COMMENT_BODY TRUE
J 0
(-14475 -50);
DISPLAY 0.872340 (-14475 -50);
PAINT PEACH (-14475 -50);
DISPLAY INVISIBLE (-14475 -50);
FORCEPROP 2 LAST PATH I67
J 0
(-14850 75);
DISPLAY 1.021277 (-14850 75);
DISPLAY INVISIBLE (-14850 75);
FORCEADD OFFPAGE..6
(-14575 75);
FORCEPROP 2 LAST $XR0 241 
J 0
(-14855 75);
DISPLAY 0.638298 (-14855 75);
PAINT MONO (-14855 75);
FORCEPROP 2 LAST CDS_LIB standard
J 0
(-14575 75);
DISPLAY INVISIBLE (-14575 75);
FORCEPROP 1 LAST COMMENT_BODY TRUE
J 0
(-14475 0);
DISPLAY 0.872340 (-14475 0);
PAINT PEACH (-14475 0);
DISPLAY INVISIBLE (-14475 0);
FORCEPROP 1 LAST OFFPAGE TRUE
J 0
(-14250 -50);
DISPLAY 0.872340 (-14250 -50);
PAINT GREEN (-14250 -50);
DISPLAY INVISIBLE (-14250 -50);
FORCEPROP 2 LAST PATH I68
J 0
(-14850 125);
DISPLAY 1.021277 (-14850 125);
DISPLAY INVISIBLE (-14850 125);
FORCEADD OFFPAGE..1
(-14550 675);
FORCEPROP 2 LAST $XR0 179 
J 0
(-14802 675);
DISPLAY 0.638298 (-14802 675);
PAINT MONO (-14802 675);
FORCEPROP 2 LAST CDS_LIB standard
J 0
(-14550 675);
DISPLAY INVISIBLE (-14550 675);
FORCEPROP 1 LAST OFFPAGE TRUE
J 0
(-14225 550);
DISPLAY 0.872340 (-14225 550);
PAINT GREEN (-14225 550);
DISPLAY INVISIBLE (-14225 550);
FORCEPROP 1 LAST COMMENT_BODY TRUE
J 0
(-14425 575);
DISPLAY 0.872340 (-14425 575);
PAINT PEACH (-14425 575);
DISPLAY INVISIBLE (-14425 575);
FORCEPROP 2 LAST PATH I69
J 0
(-14800 725);
DISPLAY 1.021277 (-14800 725);
DISPLAY INVISIBLE (-14800 725);
FORCEADD OFFPAGE..1
(-14575 -1475);
FORCEPROP 2 LAST $XR0 240 
J 0
(-14857 -1475);
DISPLAY 0.638298 (-14857 -1475);
PAINT MONO (-14857 -1475);
FORCEPROP 2 LAST CDS_LIB standard
J 0
(-14575 -1475);
DISPLAY INVISIBLE (-14575 -1475);
FORCEPROP 1 LAST OFFPAGE TRUE
J 0
(-14250 -1600);
DISPLAY 0.872340 (-14250 -1600);
PAINT GREEN (-14250 -1600);
DISPLAY INVISIBLE (-14250 -1600);
FORCEPROP 1 LAST COMMENT_BODY TRUE
J 0
(-14450 -1575);
DISPLAY 0.872340 (-14450 -1575);
PAINT PEACH (-14450 -1575);
DISPLAY INVISIBLE (-14450 -1575);
FORCEPROP 2 LAST PATH I7
J 0
(-14850 -1425);
DISPLAY 1.021277 (-14850 -1425);
DISPLAY INVISIBLE (-14850 -1425);
FORCEADD OFFPAGE..1
(-14550 725);
FORCEPROP 2 LAST $XR0 179 
J 0
(-14802 725);
DISPLAY 0.638298 (-14802 725);
PAINT MONO (-14802 725);
FORCEPROP 2 LAST CDS_LIB standard
J 0
(-14550 725);
DISPLAY INVISIBLE (-14550 725);
FORCEPROP 1 LAST OFFPAGE TRUE
J 0
(-14225 600);
DISPLAY 0.872340 (-14225 600);
PAINT GREEN (-14225 600);
DISPLAY INVISIBLE (-14225 600);
FORCEPROP 1 LAST COMMENT_BODY TRUE
J 0
(-14425 625);
DISPLAY 0.872340 (-14425 625);
PAINT PEACH (-14425 625);
DISPLAY INVISIBLE (-14425 625);
FORCEPROP 2 LAST PATH I70
J 0
(-14800 775);
DISPLAY 1.021277 (-14800 775);
DISPLAY INVISIBLE (-14800 775);
FORCEADD OFFPAGE..6
(-14550 825);
FORCEPROP 2 LAST $XR0 238 
J 0
(-14830 825);
DISPLAY 0.638298 (-14830 825);
PAINT MONO (-14830 825);
FORCEPROP 2 LAST $XR1 241 
J 0
(-14950 825);
DISPLAY 0.638298 (-14950 825);
PAINT MONO (-14950 825);
FORCEPROP 1 LAST COMMENT_BODY TRUE
J 0
(-14450 750);
DISPLAY 0.872340 (-14450 750);
PAINT PEACH (-14450 750);
DISPLAY INVISIBLE (-14450 750);
FORCEPROP 1 LAST OFFPAGE TRUE
J 0
(-14225 700);
DISPLAY 0.872340 (-14225 700);
PAINT GREEN (-14225 700);
DISPLAY INVISIBLE (-14225 700);
FORCEPROP 2 LAST CDS_LIB standard
J 0
(-14550 825);
DISPLAY INVISIBLE (-14550 825);
FORCEPROP 2 LAST PATH I71
J 0
(-14825 875);
DISPLAY 1.021277 (-14825 875);
DISPLAY INVISIBLE (-14825 875);
FORCEADD OFFPAGE..6
(-14550 875);
FORCEPROP 2 LAST $XR0 241 
J 0
(-14830 875);
DISPLAY 0.638298 (-14830 875);
PAINT MONO (-14830 875);
FORCEPROP 2 LAST $XR1 238 
J 0
(-14950 875);
DISPLAY 0.638298 (-14950 875);
PAINT MONO (-14950 875);
FORCEPROP 1 LAST COMMENT_BODY TRUE
J 0
(-14450 800);
DISPLAY 0.872340 (-14450 800);
PAINT PEACH (-14450 800);
DISPLAY INVISIBLE (-14450 800);
FORCEPROP 1 LAST OFFPAGE TRUE
J 0
(-14225 750);
DISPLAY 0.872340 (-14225 750);
PAINT GREEN (-14225 750);
DISPLAY INVISIBLE (-14225 750);
FORCEPROP 2 LAST CDS_LIB standard
J 0
(-14550 875);
DISPLAY INVISIBLE (-14550 875);
FORCEPROP 2 LAST PATH I72
J 0
(-14825 925);
DISPLAY 1.021277 (-14825 925);
DISPLAY INVISIBLE (-14825 925);
FORCEADD OFFPAGE..6
(-14550 1025);
FORCEPROP 2 LAST $XR0 183 
J 0
(-14830 1025);
DISPLAY 0.638298 (-14830 1025);
PAINT MONO (-14830 1025);
FORCEPROP 2 LAST $XR1 241 
J 0
(-14950 1025);
DISPLAY 0.638298 (-14950 1025);
PAINT MONO (-14950 1025);
FORCEPROP 2 LAST CDS_LIB standard
J 0
(-14550 1025);
DISPLAY INVISIBLE (-14550 1025);
FORCEPROP 1 LAST OFFPAGE TRUE
J 0
(-14225 900);
DISPLAY 0.872340 (-14225 900);
PAINT GREEN (-14225 900);
DISPLAY INVISIBLE (-14225 900);
FORCEPROP 1 LAST COMMENT_BODY TRUE
J 0
(-14450 950);
DISPLAY 0.872340 (-14450 950);
PAINT PEACH (-14450 950);
DISPLAY INVISIBLE (-14450 950);
FORCEPROP 2 LAST PATH I73
J 0
(-14825 1075);
DISPLAY 1.021277 (-14825 1075);
DISPLAY INVISIBLE (-14825 1075);
FORCEADD OFFPAGE..6
(-14550 1075);
FORCEPROP 2 LAST $XR0 241 
J 0
(-14830 1075);
DISPLAY 0.638298 (-14830 1075);
PAINT MONO (-14830 1075);
FORCEPROP 2 LAST $XR1 183 
J 0
(-14950 1075);
DISPLAY 0.638298 (-14950 1075);
PAINT MONO (-14950 1075);
FORCEPROP 2 LAST CDS_LIB standard
J 0
(-14550 1075);
DISPLAY INVISIBLE (-14550 1075);
FORCEPROP 1 LAST OFFPAGE TRUE
J 0
(-14225 950);
DISPLAY 0.872340 (-14225 950);
PAINT GREEN (-14225 950);
DISPLAY INVISIBLE (-14225 950);
FORCEPROP 1 LAST COMMENT_BODY TRUE
J 0
(-14450 1000);
DISPLAY 0.872340 (-14450 1000);
PAINT PEACH (-14450 1000);
DISPLAY INVISIBLE (-14450 1000);
FORCEPROP 2 LAST PATH I74
J 0
(-14825 1125);
DISPLAY 1.021277 (-14825 1125);
DISPLAY INVISIBLE (-14825 1125);
FORCEADD OFFPAGE..6
(-14550 1125);
FORCEPROP 2 LAST $XR0 233 
J 0
(-14830 1125);
DISPLAY 0.638298 (-14830 1125);
PAINT MONO (-14830 1125);
FORCEPROP 1 LAST COMMENT_BODY TRUE
J 0
(-14450 1050);
DISPLAY 0.872340 (-14450 1050);
PAINT PEACH (-14450 1050);
DISPLAY INVISIBLE (-14450 1050);
FORCEPROP 1 LAST OFFPAGE TRUE
J 0
(-14225 1000);
DISPLAY 0.872340 (-14225 1000);
PAINT GREEN (-14225 1000);
DISPLAY INVISIBLE (-14225 1000);
FORCEPROP 2 LAST CDS_LIB standard
J 0
(-14550 1125);
DISPLAY INVISIBLE (-14550 1125);
FORCEPROP 2 LAST PATH I75
J 0
(-14825 1175);
DISPLAY 1.021277 (-14825 1175);
DISPLAY INVISIBLE (-14825 1175);
FORCEADD OFFPAGE..6
(-14550 1175);
FORCEPROP 2 LAST $XR0 233 
J 0
(-14830 1175);
DISPLAY 0.638298 (-14830 1175);
PAINT MONO (-14830 1175);
FORCEPROP 1 LAST COMMENT_BODY TRUE
J 0
(-14450 1100);
DISPLAY 0.872340 (-14450 1100);
PAINT PEACH (-14450 1100);
DISPLAY INVISIBLE (-14450 1100);
FORCEPROP 1 LAST OFFPAGE TRUE
J 0
(-14225 1050);
DISPLAY 0.872340 (-14225 1050);
PAINT GREEN (-14225 1050);
DISPLAY INVISIBLE (-14225 1050);
FORCEPROP 2 LAST CDS_LIB standard
J 0
(-14550 1175);
DISPLAY INVISIBLE (-14550 1175);
FORCEPROP 2 LAST PATH I76
J 0
(-14825 1225);
DISPLAY 1.021277 (-14825 1225);
DISPLAY INVISIBLE (-14825 1225);
FORCEADD OFFPAGE..6
(-14550 1225);
FORCEPROP 2 LAST $XR0 241 
J 0
(-14830 1225);
DISPLAY 0.638298 (-14830 1225);
PAINT MONO (-14830 1225);
FORCEPROP 1 LAST COMMENT_BODY TRUE
J 0
(-14450 1150);
DISPLAY 0.872340 (-14450 1150);
PAINT PEACH (-14450 1150);
DISPLAY INVISIBLE (-14450 1150);
FORCEPROP 1 LAST OFFPAGE TRUE
J 0
(-14225 1100);
DISPLAY 0.872340 (-14225 1100);
PAINT GREEN (-14225 1100);
DISPLAY INVISIBLE (-14225 1100);
FORCEPROP 2 LAST CDS_LIB standard
J 0
(-14550 1225);
DISPLAY INVISIBLE (-14550 1225);
FORCEPROP 2 LAST PATH I77
J 0
(-14825 1275);
DISPLAY 1.021277 (-14825 1275);
DISPLAY INVISIBLE (-14825 1275);
FORCEADD OFFPAGE..6
(-14550 1275);
FORCEPROP 2 LAST $XR0 241 
J 0
(-14830 1275);
DISPLAY 0.638298 (-14830 1275);
PAINT MONO (-14830 1275);
FORCEPROP 1 LAST COMMENT_BODY TRUE
J 0
(-14450 1200);
DISPLAY 0.872340 (-14450 1200);
PAINT PEACH (-14450 1200);
DISPLAY INVISIBLE (-14450 1200);
FORCEPROP 1 LAST OFFPAGE TRUE
J 0
(-14225 1150);
DISPLAY 0.872340 (-14225 1150);
PAINT GREEN (-14225 1150);
DISPLAY INVISIBLE (-14225 1150);
FORCEPROP 2 LAST CDS_LIB standard
J 0
(-14550 1275);
DISPLAY INVISIBLE (-14550 1275);
FORCEPROP 2 LAST PATH I78
J 0
(-14825 1325);
DISPLAY 1.021277 (-14825 1325);
DISPLAY INVISIBLE (-14825 1325);
FORCEADD OFFPAGE..6
(-14525 1325);
FORCEPROP 2 LAST $XR0 238 
J 0
(-14805 1325);
DISPLAY 0.638298 (-14805 1325);
PAINT MONO (-14805 1325);
FORCEPROP 2 LAST $XR1 241 
J 0
(-14925 1325);
DISPLAY 0.638298 (-14925 1325);
PAINT MONO (-14925 1325);
FORCEPROP 2 LAST CDS_LIB standard
J 0
(-14525 1325);
DISPLAY INVISIBLE (-14525 1325);
FORCEPROP 1 LAST COMMENT_BODY TRUE
J 0
(-14425 1250);
DISPLAY 0.872340 (-14425 1250);
PAINT PEACH (-14425 1250);
DISPLAY INVISIBLE (-14425 1250);
FORCEPROP 1 LAST OFFPAGE TRUE
J 0
(-14200 1200);
DISPLAY 0.872340 (-14200 1200);
PAINT GREEN (-14200 1200);
DISPLAY INVISIBLE (-14200 1200);
FORCEPROP 2 LAST PATH I79
J 0
(-14800 1375);
DISPLAY 1.021277 (-14800 1375);
DISPLAY INVISIBLE (-14800 1375);
FORCEADD OFFPAGE..1
(-14575 -1375);
FORCEPROP 2 LAST $XR0 214 
J 0
(-14857 -1375);
DISPLAY 0.638298 (-14857 -1375);
PAINT MONO (-14857 -1375);
FORCEPROP 2 LAST CDS_LIB standard
J 0
(-14575 -1375);
DISPLAY INVISIBLE (-14575 -1375);
FORCEPROP 1 LAST COMMENT_BODY TRUE
J 0
(-14450 -1475);
DISPLAY 0.872340 (-14450 -1475);
PAINT PEACH (-14450 -1475);
DISPLAY INVISIBLE (-14450 -1475);
FORCEPROP 1 LAST OFFPAGE TRUE
J 0
(-14250 -1500);
DISPLAY 0.872340 (-14250 -1500);
PAINT GREEN (-14250 -1500);
DISPLAY INVISIBLE (-14250 -1500);
FORCEPROP 2 LAST PATH I8
J 0
(-14850 -1325);
DISPLAY 1.021277 (-14850 -1325);
DISPLAY INVISIBLE (-14850 -1325);
FORCEADD OFFPAGE..6
(-14525 1375);
FORCEPROP 2 LAST $XR0 241 
J 0
(-14805 1375);
DISPLAY 0.638298 (-14805 1375);
PAINT MONO (-14805 1375);
FORCEPROP 2 LAST $XR1 238 
J 0
(-14925 1375);
DISPLAY 0.638298 (-14925 1375);
PAINT MONO (-14925 1375);
FORCEPROP 1 LAST OFFPAGE TRUE
J 0
(-14200 1250);
DISPLAY 0.872340 (-14200 1250);
PAINT GREEN (-14200 1250);
DISPLAY INVISIBLE (-14200 1250);
FORCEPROP 1 LAST COMMENT_BODY TRUE
J 0
(-14425 1300);
DISPLAY 0.872340 (-14425 1300);
PAINT PEACH (-14425 1300);
DISPLAY INVISIBLE (-14425 1300);
FORCEPROP 2 LAST CDS_LIB standard
J 0
(-14525 1375);
DISPLAY INVISIBLE (-14525 1375);
FORCEPROP 2 LAST PATH I80
J 0
(-14800 1425);
DISPLAY 1.021277 (-14800 1425);
DISPLAY INVISIBLE (-14800 1425);
FORCEADD UNIVERSAL_GND..1
(-14975 1950);
FORCEPROP 3 LASTPIN (-14975 2000) SIG_NAME GND\g
J 0
(-14965 2010);
DISPLAY 0.659574 (-14965 2010);
PAINT MONO (-14965 2010);
DISPLAY INVISIBLE (-14965 2010);
FORCEPROP 1 LAST HDL_POWER GND
J 1
(-14950 1875);
DISPLAY 0.872340 (-14950 1875);
PAINT GREEN (-14950 1875);
DISPLAY INVISIBLE (-14950 1875);
FORCEPROP 2 LAST CDS_LIB logical_power
J 0
(-14975 1950);
PAINT MONO (-14975 1950);
DISPLAY INVISIBLE (-14975 1950);
FORCEPROP 1 LAST PATH I81
J 0
(-14900 1950);
DISPLAY 0.872340 (-14900 1950);
PAINT AQUA (-14900 1950);
DISPLAY INVISIBLE (-14900 1950);
FORCEADD Q_CAP..1
(-14975 2175);
FORCEPROP 1 LAST PART_NUMBER CH622KMEB01
J 0
(-14925 2025);
DISPLAY 0.638298 (-14925 2025);
DISPLAY INVISIBLE (-14925 2025);
FORCEPROP 1 LAST TOLERANCE 20%
J 0
(-14925 2125);
DISPLAY 0.638298 (-14925 2125);
FORCEPROP 1 LAST VOLTAGE 4V
J 0
(-14925 2175);
DISPLAY 0.638298 (-14925 2175);
FORCEPROP 1 LAST PACK_TYPE C0402
J 0
(-14925 1975);
DISPLAY 0.638298 (-14925 1975);
FORCEPROP 1 LAST MATERIAL X6S
J 0
(-14925 2075);
DISPLAY 0.638298 (-14925 2075);
FORCEPROP 1 LAST VALUE 22UF
J 0
(-14925 2225);
DISPLAY 0.638298 (-14925 2225);
FORCEPROP 1 LAST LOCATION C1302
J 0
(-14925 2275);
DISPLAY 0.978723 (-14925 2275);
FORCEPROP 1 LASTPIN (-14975 2275) $PN 1
J 0
(-14965 2255);
DISPLAY 0.787234 (-14965 2255);
PAINT MONO (-14965 2255);
FORCEPROP 1 LASTPIN (-14975 2075) $PN 2
J 0
(-14965 2055);
DISPLAY 0.787234 (-14965 2055);
PAINT MONO (-14965 2055);
FORCEPROP 2 LAST CDS_LIB pure_quanta
J 0
(-14975 2175);
DISPLAY INVISIBLE (-14975 2175);
FORCEPROP 1 LAST PATH I82
J 0
(-14925 2325);
DISPLAY 0.978723 (-14925 2325);
PAINT WHITE (-14925 2325);
DISPLAY INVISIBLE (-14925 2325);
FORCEPROP 0 LAST $SEC 1
J 0
(-14925 2325);
DISPLAY 0.680851 (-14925 2325);
PAINT MONO (-14925 2325);
DISPLAY INVISIBLE (-14925 2325);
FORCEPROP 0 LAST CDS_SEC 1
J 0
(-14925 2325);
DISPLAY 1.021277 (-14925 2325);
DISPLAY INVISIBLE (-14925 2325);
FORCEADD UNIVERSAL_POWER..1
(-14975 2525);
FORCEPROP 3 LASTPIN (-14975 2475) SIG_NAME PVNN_TERM_CPU0\g
J 0
(-14965 2485);
DISPLAY 0.659574 (-14965 2485);
PAINT MONO (-14965 2485);
DISPLAY INVISIBLE (-14965 2485);
FORCEPROP 1 LAST HDL_POWER PVNN_TERM_CPU0
J 1
(-14975 2575);
DISPLAY 0.702128 (-14975 2575);
PAINT GREEN (-14975 2575);
FORCEPROP 2 LAST CDS_LIB logical_power
J 0
(-14975 2525);
PAINT MONO (-14975 2525);
DISPLAY INVISIBLE (-14975 2525);
FORCEPROP 1 LAST PATH I83
J 0
(-14925 2550);
DISPLAY 0.872340 (-14925 2550);
PAINT AQUA (-14925 2550);
DISPLAY INVISIBLE (-14925 2550);
FORCEADD Q_RES..1
(-14625 2375);
FORCEPROP 1 LAST PART_NUMBER CS00002JB13
J 0
(-14750 2450);
DISPLAY 0.638298 (-14750 2450);
DISPLAY INVISIBLE (-14750 2450);
FORCEPROP 1 LAST WATTAGE 1/16W
J 2
(-14375 2500);
DISPLAY 0.638298 (-14375 2500);
FORCEPROP 1 LAST TOLERANCE 5%
J 0
(-14450 2375);
DISPLAY 0.638298 (-14450 2375);
FORCEPROP 1 LAST MATERIAL CHIP
J 0
(-14375 2375);
DISPLAY 0.638298 (-14375 2375);
FORCEPROP 1 LAST VALUE 0
J 2
(-14475 2375);
DISPLAY 0.638298 (-14475 2375);
FORCEPROP 1 LAST PACK_TYPE 0402LF
J 0
(-14750 2500);
DISPLAY 0.638298 (-14750 2500);
FORCEPROP 1 LAST $LOCATION R142
J 0
(-14925 2375);
DISPLAY 0.787234 (-14925 2375);
FORCEPROP 1 LASTPIN (-14725 2375) $PN 1
J 0
(-14713 2387);
DISPLAY 0.787234 (-14713 2387);
FORCEPROP 1 LASTPIN (-14525 2375) $PN 2
J 0
(-14563 2387);
DISPLAY 0.787234 (-14563 2387);
FORCEPROP 2 LAST CDS_LIB pure_quanta
J 0
(-14625 2375);
PAINT MONO (-14625 2375);
DISPLAY INVISIBLE (-14625 2375);
FORCEPROP 1 LAST PATH I84
J 0
(-14675 2525);
DISPLAY 0.978723 (-14675 2525);
PAINT WHITE (-14675 2525);
DISPLAY INVISIBLE (-14675 2525);
FORCEPROP 2 LAST CDS_LOCATION R142
J 0
(-14300 2575);
DISPLAY 1.021277 (-14300 2575);
DISPLAY INVISIBLE (-14300 2575);
FORCEPROP 2 LAST $SEC 1
J 0
(-14300 2575);
DISPLAY 0.680851 (-14300 2575);
PAINT MONO (-14300 2575);
DISPLAY INVISIBLE (-14300 2575);
FORCEPROP 2 LAST CDS_SEC 1
J 0
(-14300 2575);
DISPLAY 1.021277 (-14300 2575);
DISPLAY INVISIBLE (-14300 2575);
FORCEADD Q_RES..1
(-13300 -275);
FORCEPROP 1 LAST PART_NUMBER CS00002JB13
J 0
(-13425 -225);
DISPLAY 0.404255 (-13425 -225);
DISPLAY INVISIBLE (-13425 -225);
FORCEPROP 1 LAST VALUE 0
J 2
(-13100 -275);
DISPLAY 0.510638 (-13100 -275);
FORCEPROP 1 LAST TOLERANCE 5%
J 0
(-13075 -275);
DISPLAY 0.510638 (-13075 -275);
FORCEPROP 1 LAST MATERIAL CHIP
J 0
(-13000 -275);
DISPLAY 0.510638 (-13000 -275);
FORCEPROP 1 LAST $LOCATION R2414
J 0
(-13525 -275);
DISPLAY 0.638298 (-13525 -275);
FORCEPROP 1 LASTPIN (-13400 -275) $PN 1
J 0
(-13388 -263);
DISPLAY 0.787234 (-13388 -263);
PAINT MONO (-13388 -263);
FORCEPROP 1 LASTPIN (-13200 -275) $PN 2
J 0
(-13238 -263);
DISPLAY 0.787234 (-13238 -263);
PAINT MONO (-13238 -263);
FORCEPROP 2 LAST CDS_LIB pure_quanta
J 0
(-13300 -275);
DISPLAY INVISIBLE (-13300 -275);
FORCEPROP 1 LAST WATTAGE 1/16W
J 2
(-13200 -175);
DISPLAY 0.404255 (-13200 -175);
DISPLAY INVISIBLE (-13200 -175);
FORCEPROP 1 LAST PACK_TYPE 0402LF
J 0
(-13425 -175);
DISPLAY 0.404255 (-13425 -175);
DISPLAY INVISIBLE (-13425 -175);
FORCEPROP 1 LAST PATH I85
J 0
(-13350 -125);
DISPLAY 0.978723 (-13350 -125);
PAINT WHITE (-13350 -125);
DISPLAY INVISIBLE (-13350 -125);
FORCEPROP 0 LAST CDS_LOCATION R2414
J 0
(-13525 -225);
DISPLAY 1.021277 (-13525 -225);
DISPLAY INVISIBLE (-13525 -225);
FORCEPROP 0 LAST $SEC 1
J 0
(-13525 -225);
DISPLAY 0.680851 (-13525 -225);
PAINT MONO (-13525 -225);
DISPLAY INVISIBLE (-13525 -225);
FORCEPROP 0 LAST CDS_SEC 1
J 0
(-13525 -225);
DISPLAY 1.021277 (-13525 -225);
DISPLAY INVISIBLE (-13525 -225);
FORCEADD Q_RES..1
(-13300 -225);
FORCEPROP 1 LAST PART_NUMBER CS00002JB13
J 0
(-13425 -175);
DISPLAY 0.404255 (-13425 -175);
DISPLAY INVISIBLE (-13425 -175);
FORCEPROP 1 LAST TOLERANCE 5%
J 0
(-13075 -225);
DISPLAY 0.510638 (-13075 -225);
FORCEPROP 1 LAST VALUE 0
J 2
(-13100 -225);
DISPLAY 0.510638 (-13100 -225);
FORCEPROP 1 LAST MATERIAL CHIP
J 0
(-13000 -225);
DISPLAY 0.510638 (-13000 -225);
FORCEPROP 1 LAST $LOCATION R2413
J 0
(-13525 -225);
DISPLAY 0.638298 (-13525 -225);
FORCEPROP 1 LASTPIN (-13400 -225) $PN 1
J 0
(-13388 -213);
DISPLAY 0.787234 (-13388 -213);
PAINT MONO (-13388 -213);
FORCEPROP 1 LASTPIN (-13200 -225) $PN 2
J 0
(-13238 -213);
DISPLAY 0.787234 (-13238 -213);
PAINT MONO (-13238 -213);
FORCEPROP 2 LAST CDS_LIB pure_quanta
J 0
(-13300 -225);
DISPLAY INVISIBLE (-13300 -225);
FORCEPROP 1 LAST WATTAGE 1/16W
J 2
(-13200 -125);
DISPLAY 0.404255 (-13200 -125);
DISPLAY INVISIBLE (-13200 -125);
FORCEPROP 1 LAST PACK_TYPE 0402LF
J 0
(-13425 -125);
DISPLAY 0.404255 (-13425 -125);
DISPLAY INVISIBLE (-13425 -125);
FORCEPROP 1 LAST PATH I86
J 0
(-13350 -75);
DISPLAY 0.978723 (-13350 -75);
PAINT WHITE (-13350 -75);
DISPLAY INVISIBLE (-13350 -75);
FORCEPROP 0 LAST CDS_LOCATION R2413
J 0
(-13525 -175);
DISPLAY 1.021277 (-13525 -175);
DISPLAY INVISIBLE (-13525 -175);
FORCEPROP 0 LAST $SEC 1
J 0
(-13525 -175);
DISPLAY 0.680851 (-13525 -175);
PAINT MONO (-13525 -175);
DISPLAY INVISIBLE (-13525 -175);
FORCEPROP 0 LAST CDS_SEC 1
J 0
(-13525 -175);
DISPLAY 1.021277 (-13525 -175);
DISPLAY INVISIBLE (-13525 -175);
FORCEADD Q_RES..1
(-13275 75);
FORCEPROP 1 LAST PART_NUMBER CS03322FB03
J 0
(-13400 125);
DISPLAY 0.404255 (-13400 125);
DISPLAY INVISIBLE (-13400 125);
FORCEPROP 1 LAST MATERIAL CHIP
J 0
(-12975 75);
DISPLAY 0.510638 (-12975 75);
FORCEPROP 1 LAST TOLERANCE 1%
J 0
(-13050 75);
DISPLAY 0.510638 (-13050 75);
FORCEPROP 1 LAST VALUE 33.2
J 2
(-13075 75);
DISPLAY 0.510638 (-13075 75);
FORCEPROP 1 LAST $LOCATION R4508
J 0
(-13500 75);
DISPLAY 0.787234 (-13500 75);
FORCEPROP 1 LASTPIN (-13375 75) $PN 1
J 0
(-13363 87);
DISPLAY 0.787234 (-13363 87);
PAINT MONO (-13363 87);
FORCEPROP 1 LASTPIN (-13175 75) $PN 2
J 0
(-13213 87);
DISPLAY 0.787234 (-13213 87);
PAINT MONO (-13213 87);
FORCEPROP 2 LAST CDS_LIB pure_quanta
J 0
(-13275 75);
DISPLAY INVISIBLE (-13275 75);
FORCEPROP 1 LAST PACK_TYPE 0402LF
J 0
(-13400 175);
DISPLAY 0.404255 (-13400 175);
DISPLAY INVISIBLE (-13400 175);
FORCEPROP 1 LAST WATTAGE 1/16W
J 2
(-13175 175);
DISPLAY 0.404255 (-13175 175);
DISPLAY INVISIBLE (-13175 175);
FORCEPROP 1 LAST PATH I87
J 0
(-13325 225);
DISPLAY 0.978723 (-13325 225);
PAINT WHITE (-13325 225);
DISPLAY INVISIBLE (-13325 225);
FORCEPROP 0 LAST CDS_LOCATION R4508
J 0
(-13475 125);
DISPLAY 1.021277 (-13475 125);
DISPLAY INVISIBLE (-13475 125);
FORCEPROP 0 LAST $SEC 1
J 0
(-13475 125);
DISPLAY 0.680851 (-13475 125);
PAINT MONO (-13475 125);
DISPLAY INVISIBLE (-13475 125);
FORCEPROP 0 LAST CDS_SEC 1
J 0
(-13475 125);
DISPLAY 1.021277 (-13475 125);
DISPLAY INVISIBLE (-13475 125);
FORCEADD Q_RES..1
(-13275 25);
FORCEPROP 1 LAST PART_NUMBER CS03322FB03
J 0
(-13400 75);
DISPLAY 0.404255 (-13400 75);
DISPLAY INVISIBLE (-13400 75);
FORCEPROP 1 LAST MATERIAL CHIP
J 0
(-12975 25);
DISPLAY 0.510638 (-12975 25);
FORCEPROP 1 LAST VALUE 33.2
J 2
(-13075 25);
DISPLAY 0.510638 (-13075 25);
FORCEPROP 1 LAST TOLERANCE 1%
J 0
(-13050 25);
DISPLAY 0.510638 (-13050 25);
FORCEPROP 1 LAST $LOCATION R4509
J 0
(-13500 25);
DISPLAY 0.787234 (-13500 25);
FORCEPROP 1 LASTPIN (-13375 25) $PN 1
J 0
(-13363 37);
DISPLAY 0.787234 (-13363 37);
PAINT MONO (-13363 37);
FORCEPROP 1 LASTPIN (-13175 25) $PN 2
J 0
(-13213 37);
DISPLAY 0.787234 (-13213 37);
PAINT MONO (-13213 37);
FORCEPROP 2 LAST CDS_LIB pure_quanta
J 0
(-13275 25);
DISPLAY INVISIBLE (-13275 25);
FORCEPROP 1 LAST PACK_TYPE 0402LF
J 0
(-13400 125);
DISPLAY 0.404255 (-13400 125);
DISPLAY INVISIBLE (-13400 125);
FORCEPROP 1 LAST WATTAGE 1/16W
J 2
(-13175 125);
DISPLAY 0.404255 (-13175 125);
DISPLAY INVISIBLE (-13175 125);
FORCEPROP 1 LAST PATH I88
J 0
(-13325 175);
DISPLAY 0.978723 (-13325 175);
PAINT WHITE (-13325 175);
DISPLAY INVISIBLE (-13325 175);
FORCEPROP 0 LAST CDS_LOCATION R4509
J 0
(-13475 75);
DISPLAY 1.021277 (-13475 75);
DISPLAY INVISIBLE (-13475 75);
FORCEPROP 0 LAST $SEC 1
J 0
(-13475 75);
DISPLAY 0.680851 (-13475 75);
PAINT MONO (-13475 75);
DISPLAY INVISIBLE (-13475 75);
FORCEPROP 0 LAST CDS_SEC 1
J 0
(-13475 75);
DISPLAY 1.021277 (-13475 75);
DISPLAY INVISIBLE (-13475 75);
FORCEADD Q_RES..1
(-13275 125);
FORCEPROP 1 LAST PART_NUMBER CS03322FB03
J 0
(-13400 175);
DISPLAY 0.404255 (-13400 175);
DISPLAY INVISIBLE (-13400 175);
FORCEPROP 1 LAST MATERIAL CHIP
J 0
(-12975 125);
DISPLAY 0.510638 (-12975 125);
FORCEPROP 1 LAST VALUE 33.2
J 2
(-13075 125);
DISPLAY 0.510638 (-13075 125);
FORCEPROP 1 LAST TOLERANCE 1%
J 0
(-13050 125);
DISPLAY 0.510638 (-13050 125);
FORCEPROP 1 LAST $LOCATION R4507
J 0
(-13500 125);
DISPLAY 0.787234 (-13500 125);
FORCEPROP 1 LASTPIN (-13375 125) $PN 1
J 0
(-13363 137);
DISPLAY 0.787234 (-13363 137);
PAINT MONO (-13363 137);
FORCEPROP 1 LASTPIN (-13175 125) $PN 2
J 0
(-13213 137);
DISPLAY 0.787234 (-13213 137);
PAINT MONO (-13213 137);
FORCEPROP 1 LAST WATTAGE 1/16W
J 2
(-13175 225);
DISPLAY 0.404255 (-13175 225);
DISPLAY INVISIBLE (-13175 225);
FORCEPROP 1 LAST PACK_TYPE 0402LF
J 0
(-13400 225);
DISPLAY 0.404255 (-13400 225);
DISPLAY INVISIBLE (-13400 225);
FORCEPROP 2 LAST CDS_LIB pure_quanta
J 0
(-13275 125);
DISPLAY INVISIBLE (-13275 125);
FORCEPROP 1 LAST PATH I89
J 0
(-13325 275);
DISPLAY 0.978723 (-13325 275);
PAINT WHITE (-13325 275);
DISPLAY INVISIBLE (-13325 275);
FORCEPROP 0 LAST CDS_LOCATION R4507
J 0
(-13475 175);
DISPLAY 1.021277 (-13475 175);
DISPLAY INVISIBLE (-13475 175);
FORCEPROP 0 LAST $SEC 1
J 0
(-13475 175);
DISPLAY 0.680851 (-13475 175);
PAINT MONO (-13475 175);
DISPLAY INVISIBLE (-13475 175);
FORCEPROP 0 LAST CDS_SEC 1
J 0
(-13475 175);
DISPLAY 1.021277 (-13475 175);
DISPLAY INVISIBLE (-13475 175);
FORCEADD OFFPAGE..1
(-14325 -1175);
FORCEPROP 2 LAST $XR0 222 
J 0
(-14577 -1175);
DISPLAY 0.638298 (-14577 -1175);
PAINT MONO (-14577 -1175);
FORCEPROP 2 LAST $XR1 182 
J 0
(-14697 -1175);
DISPLAY 0.638298 (-14697 -1175);
PAINT MONO (-14697 -1175);
FORCEPROP 2 LAST $XR2 219 
J 0
(-14817 -1175);
DISPLAY 0.638298 (-14817 -1175);
PAINT MONO (-14817 -1175);
FORCEPROP 1 LAST OFFPAGE TRUE
J 0
(-14000 -1300);
DISPLAY 0.872340 (-14000 -1300);
PAINT GREEN (-14000 -1300);
DISPLAY INVISIBLE (-14000 -1300);
FORCEPROP 1 LAST COMMENT_BODY TRUE
J 0
(-14200 -1275);
DISPLAY 0.872340 (-14200 -1275);
PAINT PEACH (-14200 -1275);
DISPLAY INVISIBLE (-14200 -1275);
FORCEPROP 2 LAST CDS_LIB standard
J 0
(-14325 -1175);
PAINT MONO (-14325 -1175);
DISPLAY INVISIBLE (-14325 -1175);
FORCEPROP 2 LAST PATH I9
J 0
(-14575 -1125);
DISPLAY 1.021277 (-14575 -1125);
DISPLAY INVISIBLE (-14575 -1125);
FORCEADD Q_RES..1
(-13275 175);
FORCEPROP 1 LAST PART_NUMBER CS03322FB03
J 0
(-13400 225);
DISPLAY 0.404255 (-13400 225);
DISPLAY INVISIBLE (-13400 225);
FORCEPROP 1 LAST MATERIAL CHIP
J 0
(-12975 175);
DISPLAY 0.510638 (-12975 175);
FORCEPROP 1 LAST TOLERANCE 1%
J 0
(-13050 175);
DISPLAY 0.510638 (-13050 175);
FORCEPROP 1 LAST VALUE 33.2
J 2
(-13075 175);
DISPLAY 0.510638 (-13075 175);
FORCEPROP 1 LAST $LOCATION R4506
J 0
(-13500 175);
DISPLAY 0.787234 (-13500 175);
FORCEPROP 1 LASTPIN (-13375 175) $PN 1
J 0
(-13363 187);
DISPLAY 0.787234 (-13363 187);
PAINT MONO (-13363 187);
FORCEPROP 1 LASTPIN (-13175 175) $PN 2
J 0
(-13213 187);
DISPLAY 0.787234 (-13213 187);
PAINT MONO (-13213 187);
FORCEPROP 1 LAST WATTAGE 1/16W
J 2
(-13175 275);
DISPLAY 0.404255 (-13175 275);
DISPLAY INVISIBLE (-13175 275);
FORCEPROP 1 LAST PACK_TYPE 0402LF
J 0
(-13400 275);
DISPLAY 0.404255 (-13400 275);
DISPLAY INVISIBLE (-13400 275);
FORCEPROP 2 LAST CDS_LIB pure_quanta
J 0
(-13275 175);
DISPLAY INVISIBLE (-13275 175);
FORCEPROP 1 LAST PATH I90
J 0
(-13325 325);
DISPLAY 0.978723 (-13325 325);
PAINT WHITE (-13325 325);
DISPLAY INVISIBLE (-13325 325);
FORCEPROP 0 LAST CDS_LOCATION R4506
J 0
(-13475 225);
DISPLAY 1.021277 (-13475 225);
DISPLAY INVISIBLE (-13475 225);
FORCEPROP 0 LAST $SEC 1
J 0
(-13475 225);
DISPLAY 0.680851 (-13475 225);
PAINT MONO (-13475 225);
DISPLAY INVISIBLE (-13475 225);
FORCEPROP 0 LAST CDS_SEC 1
J 0
(-13475 225);
DISPLAY 1.021277 (-13475 225);
DISPLAY INVISIBLE (-13475 225);
FORCEADD Q_RES..1
(-13275 725);
FORCEPROP 1 LAST PART_NUMBER CS01002FB07
J 0
(-13400 775);
DISPLAY 0.404255 (-13400 775);
DISPLAY INVISIBLE (-13400 775);
FORCEPROP 1 LAST MATERIAL CHIP
J 0
(-12975 725);
DISPLAY 0.510638 (-12975 725);
FORCEPROP 1 LAST VALUE 10
J 2
(-13075 725);
DISPLAY 0.510638 (-13075 725);
FORCEPROP 1 LAST $LOCATION R4535
J 0
(-13500 725);
DISPLAY 0.638298 (-13500 725);
FORCEPROP 1 LASTPIN (-13375 725) $PN 1
J 0
(-13363 737);
DISPLAY 0.787234 (-13363 737);
PAINT MONO (-13363 737);
FORCEPROP 1 LASTPIN (-13175 725) $PN 2
J 0
(-13213 737);
DISPLAY 0.787234 (-13213 737);
PAINT MONO (-13213 737);
FORCEPROP 1 LAST WATTAGE 1/16W
J 2
(-13175 825);
DISPLAY 0.404255 (-13175 825);
DISPLAY INVISIBLE (-13175 825);
FORCEPROP 1 LAST TOLERANCE 1%
J 0
(-13050 725);
DISPLAY 0.510638 (-13050 725);
DISPLAY INVISIBLE (-13050 725);
FORCEPROP 1 LAST PACK_TYPE 0402LF
J 0
(-13400 825);
DISPLAY 0.404255 (-13400 825);
DISPLAY INVISIBLE (-13400 825);
FORCEPROP 2 LAST CDS_LIB pure_quanta
J 0
(-13275 725);
DISPLAY INVISIBLE (-13275 725);
FORCEPROP 1 LAST PATH I91
J 0
(-13325 875);
DISPLAY 0.978723 (-13325 875);
PAINT WHITE (-13325 875);
DISPLAY INVISIBLE (-13325 875);
FORCEPROP 0 LAST CDS_LOCATION R4535
J 0
(-13175 850);
DISPLAY 1.021277 (-13175 850);
DISPLAY INVISIBLE (-13175 850);
FORCEPROP 0 LAST $SEC 1
J 0
(-13175 850);
DISPLAY 0.680851 (-13175 850);
PAINT MONO (-13175 850);
DISPLAY INVISIBLE (-13175 850);
FORCEPROP 0 LAST CDS_SEC 1
J 0
(-13175 850);
DISPLAY 1.021277 (-13175 850);
DISPLAY INVISIBLE (-13175 850);
FORCEADD Q_RES..1
(-13275 675);
FORCEPROP 1 LAST PART_NUMBER CS01002FB07
J 0
(-13400 725);
DISPLAY 0.404255 (-13400 725);
DISPLAY INVISIBLE (-13400 725);
FORCEPROP 1 LAST TOLERANCE 1%
J 0
(-13050 675);
DISPLAY 0.510638 (-13050 675);
FORCEPROP 1 LAST VALUE 10
J 2
(-13075 675);
DISPLAY 0.510638 (-13075 675);
FORCEPROP 1 LAST MATERIAL CHIP
J 0
(-12975 675);
DISPLAY 0.510638 (-12975 675);
FORCEPROP 1 LAST $LOCATION R4536
J 0
(-13500 675);
DISPLAY 0.638298 (-13500 675);
FORCEPROP 1 LASTPIN (-13375 675) $PN 1
J 0
(-13363 687);
DISPLAY 0.787234 (-13363 687);
PAINT MONO (-13363 687);
FORCEPROP 1 LASTPIN (-13175 675) $PN 2
J 0
(-13213 687);
DISPLAY 0.787234 (-13213 687);
PAINT MONO (-13213 687);
FORCEPROP 1 LAST WATTAGE 1/16W
J 2
(-13175 775);
DISPLAY 0.404255 (-13175 775);
DISPLAY INVISIBLE (-13175 775);
FORCEPROP 1 LAST PACK_TYPE 0402LF
J 0
(-13400 775);
DISPLAY 0.404255 (-13400 775);
DISPLAY INVISIBLE (-13400 775);
FORCEPROP 2 LAST CDS_LIB pure_quanta
J 0
(-13275 675);
DISPLAY INVISIBLE (-13275 675);
FORCEPROP 1 LAST PATH I92
J 0
(-13325 825);
DISPLAY 0.978723 (-13325 825);
PAINT WHITE (-13325 825);
DISPLAY INVISIBLE (-13325 825);
FORCEPROP 0 LAST CDS_LOCATION R4536
J 0
(-13500 725);
DISPLAY 1.021277 (-13500 725);
DISPLAY INVISIBLE (-13500 725);
FORCEPROP 0 LAST $SEC 1
J 0
(-13500 725);
DISPLAY 0.680851 (-13500 725);
PAINT MONO (-13500 725);
DISPLAY INVISIBLE (-13500 725);
FORCEPROP 0 LAST CDS_SEC 1
J 0
(-13500 725);
DISPLAY 1.021277 (-13500 725);
DISPLAY INVISIBLE (-13500 725);
FORCEADD Q_RES..1
(-13275 875);
FORCEPROP 1 LAST PART_NUMBER CS03322FB03
J 0
(-13400 925);
DISPLAY 0.404255 (-13400 925);
DISPLAY INVISIBLE (-13400 925);
FORCEPROP 1 LAST MATERIAL CHIP
J 0
(-12975 875);
DISPLAY 0.510638 (-12975 875);
FORCEPROP 1 LAST VALUE 33.2
J 2
(-13075 875);
DISPLAY 0.510638 (-13075 875);
FORCEPROP 1 LAST TOLERANCE 1%
J 0
(-13050 875);
DISPLAY 0.510638 (-13050 875);
FORCEPROP 1 LAST $LOCATION R2425
J 0
(-13500 875);
DISPLAY 0.638298 (-13500 875);
FORCEPROP 1 LASTPIN (-13375 875) $PN 1
J 0
(-13363 887);
DISPLAY 0.787234 (-13363 887);
PAINT MONO (-13363 887);
FORCEPROP 1 LASTPIN (-13175 875) $PN 2
J 0
(-13213 887);
DISPLAY 0.787234 (-13213 887);
PAINT MONO (-13213 887);
FORCEPROP 1 LAST WATTAGE 1/16W
J 2
(-13175 975);
DISPLAY 0.404255 (-13175 975);
DISPLAY INVISIBLE (-13175 975);
FORCEPROP 1 LAST PACK_TYPE 0402LF
J 0
(-13400 975);
DISPLAY 0.404255 (-13400 975);
DISPLAY INVISIBLE (-13400 975);
FORCEPROP 2 LAST CDS_LIB pure_quanta
J 0
(-13275 875);
DISPLAY INVISIBLE (-13275 875);
FORCEPROP 1 LAST PATH I93
J 0
(-13325 1025);
DISPLAY 0.978723 (-13325 1025);
PAINT WHITE (-13325 1025);
DISPLAY INVISIBLE (-13325 1025);
FORCEPROP 0 LAST CDS_LOCATION R2425
J 0
(-13500 925);
DISPLAY 1.021277 (-13500 925);
DISPLAY INVISIBLE (-13500 925);
FORCEPROP 0 LAST $SEC 1
J 0
(-13500 925);
DISPLAY 0.680851 (-13500 925);
PAINT MONO (-13500 925);
DISPLAY INVISIBLE (-13500 925);
FORCEPROP 0 LAST CDS_SEC 1
J 0
(-13500 925);
DISPLAY 1.021277 (-13500 925);
DISPLAY INVISIBLE (-13500 925);
FORCEADD Q_RES..1
(-13275 825);
FORCEPROP 1 LAST PART_NUMBER CS03322FB03
J 0
(-13400 875);
DISPLAY 0.404255 (-13400 875);
DISPLAY INVISIBLE (-13400 875);
FORCEPROP 1 LAST MATERIAL CHIP
J 0
(-12975 825);
DISPLAY 0.510638 (-12975 825);
FORCEPROP 1 LAST TOLERANCE 1%
J 0
(-13050 825);
DISPLAY 0.510638 (-13050 825);
FORCEPROP 1 LAST VALUE 33.2
J 2
(-13075 825);
DISPLAY 0.510638 (-13075 825);
FORCEPROP 1 LAST $LOCATION R3858
J 0
(-13500 825);
DISPLAY 0.638298 (-13500 825);
FORCEPROP 1 LASTPIN (-13375 825) $PN 1
J 0
(-13363 837);
DISPLAY 0.787234 (-13363 837);
PAINT MONO (-13363 837);
FORCEPROP 1 LASTPIN (-13175 825) $PN 2
J 0
(-13213 837);
DISPLAY 0.787234 (-13213 837);
PAINT MONO (-13213 837);
FORCEPROP 1 LAST WATTAGE 1/16W
J 2
(-13175 925);
DISPLAY 0.404255 (-13175 925);
DISPLAY INVISIBLE (-13175 925);
FORCEPROP 1 LAST PACK_TYPE 0402LF
J 0
(-13400 925);
DISPLAY 0.404255 (-13400 925);
DISPLAY INVISIBLE (-13400 925);
FORCEPROP 2 LAST CDS_LIB pure_quanta
J 0
(-13275 825);
DISPLAY INVISIBLE (-13275 825);
FORCEPROP 1 LAST PATH I94
J 0
(-13325 975);
DISPLAY 0.978723 (-13325 975);
PAINT WHITE (-13325 975);
DISPLAY INVISIBLE (-13325 975);
FORCEPROP 0 LAST CDS_LOCATION R3858
J 0
(-13500 875);
DISPLAY 1.021277 (-13500 875);
DISPLAY INVISIBLE (-13500 875);
FORCEPROP 0 LAST $SEC 1
J 0
(-13500 875);
DISPLAY 0.680851 (-13500 875);
PAINT MONO (-13500 875);
DISPLAY INVISIBLE (-13500 875);
FORCEPROP 0 LAST CDS_SEC 1
J 0
(-13500 875);
DISPLAY 1.021277 (-13500 875);
DISPLAY INVISIBLE (-13500 875);
FORCEADD Q_RES..1
(-13275 1125);
FORCEPROP 1 LAST PART_NUMBER CS03322FB03
J 0
(-13400 1175);
DISPLAY 0.404255 (-13400 1175);
DISPLAY INVISIBLE (-13400 1175);
FORCEPROP 1 LAST TOLERANCE 1%
J 0
(-13050 1125);
DISPLAY 0.510638 (-13050 1125);
FORCEPROP 1 LAST MATERIAL CHIP
J 0
(-12975 1125);
DISPLAY 0.510638 (-12975 1125);
FORCEPROP 1 LAST VALUE 33.2
J 2
(-13075 1125);
DISPLAY 0.510638 (-13075 1125);
FORCEPROP 1 LAST $LOCATION R2422
J 0
(-13500 1125);
DISPLAY 0.638298 (-13500 1125);
FORCEPROP 1 LASTPIN (-13375 1125) $PN 1
J 0
(-13363 1137);
DISPLAY 0.787234 (-13363 1137);
PAINT MONO (-13363 1137);
FORCEPROP 1 LASTPIN (-13175 1125) $PN 2
J 0
(-13213 1137);
DISPLAY 0.787234 (-13213 1137);
PAINT MONO (-13213 1137);
FORCEPROP 2 LAST CDS_LIB pure_quanta
J 0
(-13275 1125);
DISPLAY INVISIBLE (-13275 1125);
FORCEPROP 1 LAST PACK_TYPE 0402LF
J 0
(-13400 1225);
DISPLAY 0.404255 (-13400 1225);
DISPLAY INVISIBLE (-13400 1225);
FORCEPROP 1 LAST WATTAGE 1/16W
J 2
(-13175 1225);
DISPLAY 0.404255 (-13175 1225);
DISPLAY INVISIBLE (-13175 1225);
FORCEPROP 1 LAST PATH I95
J 0
(-13325 1275);
DISPLAY 0.978723 (-13325 1275);
PAINT WHITE (-13325 1275);
DISPLAY INVISIBLE (-13325 1275);
FORCEPROP 0 LAST CDS_LOCATION R2422
J 0
(-13500 1175);
DISPLAY 1.021277 (-13500 1175);
DISPLAY INVISIBLE (-13500 1175);
FORCEPROP 0 LAST $SEC 1
J 0
(-13500 1175);
DISPLAY 0.680851 (-13500 1175);
PAINT MONO (-13500 1175);
DISPLAY INVISIBLE (-13500 1175);
FORCEPROP 0 LAST CDS_SEC 1
J 0
(-13500 1175);
DISPLAY 1.021277 (-13500 1175);
DISPLAY INVISIBLE (-13500 1175);
FORCEADD Q_RES..1
(-13275 1025);
FORCEPROP 1 LAST PART_NUMBER CS03322FB03
J 0
(-13400 1075);
DISPLAY 0.404255 (-13400 1075);
DISPLAY INVISIBLE (-13400 1075);
FORCEPROP 1 LAST VALUE 33.2
J 2
(-13075 1025);
DISPLAY 0.510638 (-13075 1025);
FORCEPROP 1 LAST MATERIAL CHIP
J 0
(-12975 1025);
DISPLAY 0.510638 (-12975 1025);
FORCEPROP 1 LAST TOLERANCE 1%
J 0
(-13050 1025);
DISPLAY 0.510638 (-13050 1025);
FORCEPROP 1 LAST $LOCATION R2424
J 0
(-13500 1025);
DISPLAY 0.638298 (-13500 1025);
FORCEPROP 1 LASTPIN (-13375 1025) $PN 1
J 0
(-13363 1037);
DISPLAY 0.787234 (-13363 1037);
PAINT MONO (-13363 1037);
FORCEPROP 1 LASTPIN (-13175 1025) $PN 2
J 0
(-13213 1037);
DISPLAY 0.787234 (-13213 1037);
PAINT MONO (-13213 1037);
FORCEPROP 1 LAST PACK_TYPE 0402LF
J 0
(-13400 1125);
DISPLAY 0.404255 (-13400 1125);
DISPLAY INVISIBLE (-13400 1125);
FORCEPROP 1 LAST WATTAGE 1/16W
J 2
(-13175 1125);
DISPLAY 0.404255 (-13175 1125);
DISPLAY INVISIBLE (-13175 1125);
FORCEPROP 2 LAST CDS_LIB pure_quanta
J 0
(-13275 1025);
DISPLAY INVISIBLE (-13275 1025);
FORCEPROP 1 LAST PATH I96
J 0
(-13325 1175);
DISPLAY 0.978723 (-13325 1175);
PAINT WHITE (-13325 1175);
DISPLAY INVISIBLE (-13325 1175);
FORCEPROP 0 LAST CDS_LOCATION R2424
J 0
(-13500 1075);
DISPLAY 1.021277 (-13500 1075);
DISPLAY INVISIBLE (-13500 1075);
FORCEPROP 0 LAST $SEC 1
J 0
(-13500 1075);
DISPLAY 0.680851 (-13500 1075);
PAINT MONO (-13500 1075);
DISPLAY INVISIBLE (-13500 1075);
FORCEPROP 0 LAST CDS_SEC 1
J 0
(-13500 1075);
DISPLAY 1.021277 (-13500 1075);
DISPLAY INVISIBLE (-13500 1075);
FORCEADD Q_RES..1
(-13275 1075);
FORCEPROP 1 LAST PART_NUMBER CS03322FB03
J 0
(-13400 1125);
DISPLAY 0.404255 (-13400 1125);
DISPLAY INVISIBLE (-13400 1125);
FORCEPROP 1 LAST VALUE 33.2
J 2
(-13075 1075);
DISPLAY 0.510638 (-13075 1075);
FORCEPROP 1 LAST TOLERANCE 1%
J 0
(-13050 1075);
DISPLAY 0.510638 (-13050 1075);
FORCEPROP 1 LAST MATERIAL CHIP
J 0
(-12975 1075);
DISPLAY 0.510638 (-12975 1075);
FORCEPROP 1 LAST $LOCATION R2423
J 0
(-13500 1075);
DISPLAY 0.638298 (-13500 1075);
FORCEPROP 1 LASTPIN (-13375 1075) $PN 1
J 0
(-13363 1087);
DISPLAY 0.787234 (-13363 1087);
PAINT MONO (-13363 1087);
FORCEPROP 1 LASTPIN (-13175 1075) $PN 2
J 0
(-13213 1087);
DISPLAY 0.787234 (-13213 1087);
PAINT MONO (-13213 1087);
FORCEPROP 1 LAST PACK_TYPE 0402LF
J 0
(-13400 1175);
DISPLAY 0.404255 (-13400 1175);
DISPLAY INVISIBLE (-13400 1175);
FORCEPROP 1 LAST WATTAGE 1/16W
J 2
(-13175 1175);
DISPLAY 0.404255 (-13175 1175);
DISPLAY INVISIBLE (-13175 1175);
FORCEPROP 2 LAST CDS_LIB pure_quanta
J 0
(-13275 1075);
DISPLAY INVISIBLE (-13275 1075);
FORCEPROP 1 LAST PATH I97
J 0
(-13325 1225);
DISPLAY 0.978723 (-13325 1225);
PAINT WHITE (-13325 1225);
DISPLAY INVISIBLE (-13325 1225);
FORCEPROP 0 LAST CDS_LOCATION R2423
J 0
(-13500 1125);
DISPLAY 1.021277 (-13500 1125);
DISPLAY INVISIBLE (-13500 1125);
FORCEPROP 0 LAST $SEC 1
J 0
(-13500 1125);
DISPLAY 0.680851 (-13500 1125);
PAINT MONO (-13500 1125);
DISPLAY INVISIBLE (-13500 1125);
FORCEPROP 0 LAST CDS_SEC 1
J 0
(-13500 1125);
DISPLAY 1.021277 (-13500 1125);
DISPLAY INVISIBLE (-13500 1125);
FORCEADD Q_RES..1
(-13275 1225);
FORCEPROP 1 LAST PART_NUMBER CS03322FB03
J 0
(-13400 1275);
DISPLAY 0.404255 (-13400 1275);
DISPLAY INVISIBLE (-13400 1275);
FORCEPROP 1 LAST VALUE 33.2
J 2
(-13075 1225);
DISPLAY 0.510638 (-13075 1225);
FORCEPROP 1 LAST TOLERANCE 1%
J 0
(-13050 1225);
DISPLAY 0.510638 (-13050 1225);
FORCEPROP 1 LAST MATERIAL CHIP
J 0
(-12975 1225);
DISPLAY 0.510638 (-12975 1225);
FORCEPROP 1 LAST $LOCATION R2420
J 0
(-13500 1225);
DISPLAY 0.638298 (-13500 1225);
FORCEPROP 1 LASTPIN (-13375 1225) $PN 1
J 0
(-13363 1237);
DISPLAY 0.787234 (-13363 1237);
PAINT MONO (-13363 1237);
FORCEPROP 1 LASTPIN (-13175 1225) $PN 2
J 0
(-13213 1237);
DISPLAY 0.787234 (-13213 1237);
PAINT MONO (-13213 1237);
FORCEPROP 1 LAST WATTAGE 1/16W
J 2
(-13175 1325);
DISPLAY 0.404255 (-13175 1325);
DISPLAY INVISIBLE (-13175 1325);
FORCEPROP 1 LAST PACK_TYPE 0402LF
J 0
(-13400 1325);
DISPLAY 0.404255 (-13400 1325);
DISPLAY INVISIBLE (-13400 1325);
FORCEPROP 2 LAST CDS_LIB pure_quanta
J 0
(-13275 1225);
DISPLAY INVISIBLE (-13275 1225);
FORCEPROP 1 LAST PATH I98
J 0
(-13325 1375);
DISPLAY 0.978723 (-13325 1375);
PAINT WHITE (-13325 1375);
DISPLAY INVISIBLE (-13325 1375);
FORCEPROP 0 LAST CDS_LOCATION R2420
J 0
(-13500 1275);
DISPLAY 1.021277 (-13500 1275);
DISPLAY INVISIBLE (-13500 1275);
FORCEPROP 0 LAST $SEC 1
J 0
(-13500 1275);
DISPLAY 0.680851 (-13500 1275);
PAINT MONO (-13500 1275);
DISPLAY INVISIBLE (-13500 1275);
FORCEPROP 0 LAST CDS_SEC 1
J 0
(-13500 1275);
DISPLAY 1.021277 (-13500 1275);
DISPLAY INVISIBLE (-13500 1275);
FORCEADD Q_RES..1
(-13275 1175);
FORCEPROP 1 LAST PART_NUMBER CS03322FB03
J 0
(-13400 1225);
DISPLAY 0.404255 (-13400 1225);
DISPLAY INVISIBLE (-13400 1225);
FORCEPROP 1 LAST VALUE 33.2
J 2
(-13075 1175);
DISPLAY 0.510638 (-13075 1175);
FORCEPROP 1 LAST MATERIAL CHIP
J 0
(-12975 1175);
DISPLAY 0.510638 (-12975 1175);
FORCEPROP 1 LAST TOLERANCE 1%
J 0
(-13050 1175);
DISPLAY 0.510638 (-13050 1175);
FORCEPROP 1 LAST $LOCATION R2421
J 0
(-13500 1175);
DISPLAY 0.638298 (-13500 1175);
FORCEPROP 1 LASTPIN (-13375 1175) $PN 1
J 0
(-13363 1187);
DISPLAY 0.787234 (-13363 1187);
PAINT MONO (-13363 1187);
FORCEPROP 1 LASTPIN (-13175 1175) $PN 2
J 0
(-13213 1187);
DISPLAY 0.787234 (-13213 1187);
PAINT MONO (-13213 1187);
FORCEPROP 2 LAST CDS_LIB pure_quanta
J 0
(-13275 1175);
DISPLAY INVISIBLE (-13275 1175);
FORCEPROP 1 LAST PACK_TYPE 0402LF
J 0
(-13400 1275);
DISPLAY 0.404255 (-13400 1275);
DISPLAY INVISIBLE (-13400 1275);
FORCEPROP 1 LAST WATTAGE 1/16W
J 2
(-13175 1275);
DISPLAY 0.404255 (-13175 1275);
DISPLAY INVISIBLE (-13175 1275);
FORCEPROP 1 LAST PATH I99
J 0
(-13325 1325);
DISPLAY 0.978723 (-13325 1325);
PAINT WHITE (-13325 1325);
DISPLAY INVISIBLE (-13325 1325);
FORCEPROP 0 LAST CDS_LOCATION R2421
J 0
(-13500 1225);
DISPLAY 1.021277 (-13500 1225);
DISPLAY INVISIBLE (-13500 1225);
FORCEPROP 0 LAST $SEC 1
J 0
(-13500 1225);
DISPLAY 0.680851 (-13500 1225);
PAINT MONO (-13500 1225);
DISPLAY INVISIBLE (-13500 1225);
FORCEPROP 0 LAST CDS_SEC 1
J 0
(-13500 1225);
DISPLAY 1.021277 (-13500 1225);
DISPLAY INVISIBLE (-13500 1225);
FORCEADD DNS..2
(-7850 -2225);
PAINT RED (-7850 -2225);
FORCEPROP 1 LAST COMMENT_BODY TRUE
J 0
(-7850 -2225);
DISPLAY INVISIBLE (-7850 -2225);
FORCEPROP 2 LAST CDS_LIB mstr_misc
J 0
(-7850 -2225);
DISPLAY INVISIBLE (-7850 -2225);
FORCEADD DNS..2
(-7850 -2175);
PAINT RED (-7850 -2175);
FORCEPROP 1 LAST COMMENT_BODY TRUE
J 0
(-7850 -2175);
DISPLAY INVISIBLE (-7850 -2175);
FORCEPROP 2 LAST CDS_LIB mstr_misc
J 0
(-7850 -2175);
DISPLAY INVISIBLE (-7850 -2175);
FORCEADD DESIGN_NOTE..1
(-9150 2800);
FORCEPROP 0 LAST L2 UART_2 BMC TO MB (BMC HOST)
J 0
(-9350 2600);
DISPLAY 0.808511 (-9350 2600);
PAINT SKYBLUE (-9350 2600);
FORCEPROP 0 LAST L1 UART_1 MB TO BMC (BMC SLAVE)
J 0
(-9350 2675);
DISPLAY 0.808511 (-9350 2675);
PAINT SKYBLUE (-9350 2675);
FORCEPROP 1 LAST COMMENT_BODY TRUE
J 0
(-9125 2900);
DISPLAY 0.978723 (-9125 2900);
DISPLAY INVISIBLE (-9125 2900);
FORCEPROP 2 LAST CDS_LIB logical_power
J 0
(-9150 2800);
DISPLAY INVISIBLE (-9150 2800);
FORCEADD DNS..2
(-8150 1775);
PAINT RED (-8150 1775);
FORCEPROP 2 LAST CDS_LIB mstr_misc
J 0
(-8150 1775);
DISPLAY INVISIBLE (-8150 1775);
FORCEPROP 1 LAST COMMENT_BODY TRUE
J 0
(-8150 1775);
DISPLAY INVISIBLE (-8150 1775);
FORCEADD DNS..2
(-8150 1825);
PAINT RED (-8150 1825);
FORCEPROP 2 LAST CDS_LIB mstr_misc
J 0
(-8150 1825);
DISPLAY INVISIBLE (-8150 1825);
FORCEPROP 1 LAST COMMENT_BODY TRUE
J 0
(-8150 1825);
DISPLAY INVISIBLE (-8150 1825);
FORCEADD QUANTA_TITLE_BLOCK_C..1
(-6100 -3575);
FORCEPROP 0 LAST CDS_CON_LAST_MODIFIED Fri Aug 25 14:04:07 2023
J 0
(-7985 -3560);
DISPLAY INVISIBLE (-7985 -3560);
FORCEPROP 2 LAST CUSTOM_TXT_CDS <XR_PAGE_TITLE>
J 0
(-13990 1675);
DISPLAY 0.638298 (-13990 1675);
PAINT PINK (-13990 1675);
DISPLAY INVISIBLE (-13990 1675);
FORCEPROP 2 LAST CUSTOM_TXT_CDS CR-210 : @S9S_MB_LIB.S9S_MB(SCH_1):PAGE210
J 0
(-13990 1675);
DISPLAY 0.638298 (-13990 1675);
PAINT PINK (-13990 1675);
DISPLAY INVISIBLE (-13990 1675);
FORCEPROP 2 LAST CUSTOM_TXT_CDS <CON_LAST_MODIFIED>
J 0
(-7985 -3560);
DISPLAY 0.978723 (-7985 -3560);
FORCEPROP 2 LAST CUSTOM_TXT_CDS <NAME_2>
J 0
(-9275 -3525);
FORCEPROP 2 LAST CUSTOM_TXT_CDS <Q_NUMBER>
J 0
(-7503 -3472);
DISPLAY 1.212766 (-7503 -3472);
FORCEPROP 2 LAST CUSTOM_TXT_CDS <Q_REV>
J 0
(-6284 -3472);
DISPLAY 1.212766 (-6284 -3472);
FORCEPROP 2 LAST CUSTOM_TXT_CDS <Q_PROJ>
J 0
(-8425 -3475);
DISPLAY 1.212766 (-8425 -3475);
FORCEPROP 2 LAST CUSTOM_TXT_CDS <CON_PAGE_NUM> OF <CON_TOTAL_PAGES>
J 0
(-6575 -3550);
DISPLAY 0.978723 (-6575 -3550);
FORCEPROP 1 LAST CUSTOM_TXT_CDS <NAME_1>
J 0
(-9275 -3400);
FORCEPROP 1 LAST Q_TITLE SCM CONN
J 0
(-15466 -3549);
DISPLAY 2.446809 (-15466 -3549);
PAINT GREEN (-15466 -3549);
FORCEPROP 1 LAST Q_DEPT 
J 1
(-9863 -3526);
DISPLAY 1.957447 (-9863 -3526);
PAINT GREEN (-9863 -3526);
FORCEPROP 1 LAST COMMENT_BODY TRUE
J 0
(-6088 -3588);
DISPLAY 0.978723 (-6088 -3588);
PAINT PEACH (-6088 -3588);
DISPLAY INVISIBLE (-6088 -3588);
FORCEPROP 1 LAST CDS_LMAN_SYM_OUTLINE -9475,6775,100,-125
J 0
(-6100 -3575);
DISPLAY 0.468085 (-6100 -3575);
PAINT GREEN (-6100 -3575);
DISPLAY INVISIBLE (-6100 -3575);
FORCEPROP 2 LAST CDS_LIB pure_quanta
J 0
(-6100 -3575);
DISPLAY INVISIBLE (-6100 -3575);
FORCEPROP 2 LAST PAGE_BORDER TRUE
J 0
(-13990 1675);
DISPLAY 0.638298 (-13990 1675);
PAINT PINK (-13990 1675);
DISPLAY INVISIBLE (-13990 1675);
FORCEPROP 2 LAST CDS_XR_PAGE_TITLE CR-240 : @S9S_MB_2U_LIB.S9S_MB_2U(SCH_1):PAGE240
J 0
(-13990 1675);
DISPLAY 0.638298 (-13990 1675);
PAINT PINK (-13990 1675);
DISPLAY INVISIBLE (-13990 1675);
WIRE 16 -1 (-14975 2375)(-14975 2475);
WIRE 16 -1 (-14725 2375)(-14975 2375);
WIRE 16 -1 (-14975 2275)(-14975 2375);
WIRE 16 -1 (-11275 2175)(-11275 2400);
WIRE 16 -1 (-11275 2125)(-11275 2175);
WIRE 16 -1 (-11050 2175)(-11275 2175);
WIRE 16 -1 (-9550 2400)(-9550 2175);
WIRE 16 -1 (-14825 -2525)(-14825 -2625);
WIRE 16 -1 (-11275 -2625)(-11275 -2575);
WIRE 16 -1 (-9550 -2550)(-9550 -2275);
WIRE 16 -1 (-14975 2000)(-14975 2075);
WIRE 16 -1 (-7625 2150)(-7625 2100);
WIRE 16 -1 (-13375 1275)(-14500 1275);
FORCEPROP 0 LAST SIG_NAME SMB_HOST_3V3AUX_SCL
J 0
(-14410 1285);
DISPLAY 0.553191 (-14410 1285);
PAINT WHITE (-14410 1285);
WIRE 16 -1 (-13375 1075)(-14500 1075);
FORCEPROP 0 LAST SIG_NAME SMB_SML1_PMBUS_3V3AUX_PCH_SCL
J 0
(-14410 1085);
DISPLAY 0.553191 (-14410 1085);
PAINT WHITE (-14410 1085);
WIRE 16 -1 (-11050 -275)(-13200 -275);
FORCEPROP 0 LAST SIG_NAME SMB_PCIE2_3V3AUX_SDA_R0
J 0
(-12310 -265);
DISPLAY 0.680851 (-12310 -265);
PAINT WHITE (-12310 -265);
WIRE 16 -1 (-11050 -575)(-13200 -575);
FORCEPROP 0 LAST SIG_NAME SMB_PCIE3_3V3AUX_SCL_R
J 0
(-12310 -565);
DISPLAY 0.680851 (-12310 -565);
PAINT WHITE (-12310 -565);
WIRE 16 -1 (-11050 -725)(-13200 -725);
FORCEPROP 2 LAST SIG_NAME SMB_S3M_CPU_3V3AUX_SDA_R0
J 0
(-12310 -715);
DISPLAY 0.638298 (-12310 -715);
PAINT WHITE (-12310 -715);
WIRE 16 -1 (-11050 -1125)(-12975 -1125);
FORCEPROP 0 LAST CDS_PHYS_NET_NAME FM_BMC_PWRBTN_OUT_R_N
J 0
(-12160 -1091);
PAINT MONO (-12160 -1091);
DISPLAY INVISIBLE (-12160 -1091);
FORCEPROP 2 LAST SIG_NAME FM_BMC_PWRBTN_OUT_R_N
J 0
(-12310 -1115);
DISPLAY 0.638298 (-12310 -1115);
PAINT WHITE (-12310 -1115);
WIRE 16 -1 (-13225 -1375)(-11050 -1375);
FORCEPROP 2 LAST SIG_NAME FM_UARTSW_MSB_R
J 0
(-12310 -1365);
DISPLAY 0.680851 (-12310 -1365);
PAINT WHITE (-12310 -1365);
WIRE 16 -1 (-13225 -1525)(-11050 -1525);
FORCEPROP 2 LAST SIG_NAME FM_UARTSW_LSB_R
J 0
(-12310 -1515);
DISPLAY 0.680851 (-12310 -1515);
PAINT WHITE (-12310 -1515);
WIRE 16 -1 (-11050 2075)(-11275 2075);
WIRE 16 -1 (-11050 2025)(-11275 2025);
WIRE 16 -1 (-11275 2025)(-11275 2075);
WIRE 16 -1 (-11275 2025)(-11275 1575);
WIRE 16 -1 (-11050 1575)(-11275 1575);
WIRE 16 -1 (-11275 1575)(-11275 775);
WIRE 16 -1 (-11050 775)(-11275 775);
WIRE 16 -1 (-11275 775)(-11275 625);
WIRE 16 -1 (-11050 625)(-11275 625);
WIRE 16 -1 (-11275 625)(-11275 475);
WIRE 16 -1 (-11050 475)(-11275 475);
WIRE 16 -1 (-11275 475)(-11275 325);
WIRE 16 -1 (-11050 325)(-11275 325);
WIRE 16 -1 (-11050 -325)(-11275 -325);
WIRE 16 -1 (-11275 325)(-11275 -325);
WIRE 16 -1 (-11275 -775)(-11275 -325);
WIRE 16 -1 (-11050 -775)(-11275 -775);
WIRE 16 -1 (-11275 -1675)(-11275 -775);
WIRE 16 -1 (-11050 -1675)(-11275 -1675);
WIRE 16 -1 (-11275 -1825)(-11275 -1675);
WIRE 16 -1 (-11050 -1825)(-11275 -1825);
WIRE 16 -1 (-11275 -1975)(-11275 -1825);
WIRE 16 -1 (-11050 -1975)(-11275 -1975);
WIRE 16 -1 (-11050 -2125)(-11275 -2125);
WIRE 16 -1 (-11275 -2125)(-11275 -1975);
WIRE 16 -1 (-11275 -2275)(-11275 -2125);
WIRE 16 -1 (-11050 -2275)(-11275 -2275);
WIRE 16 -1 (-11275 -2375)(-11275 -2275);
WIRE 16 -1 (-11050 -2375)(-11275 -2375);
WIRE 16 -1 (-11275 -2425)(-11275 -2375);
WIRE 16 -1 (-11050 -2425)(-11275 -2425);
WIRE 16 -1 (-11275 -2475)(-11275 -2425);
WIRE 16 -1 (-11050 -2475)(-11275 -2475);
WIRE 16 -1 (-11275 -2525)(-11275 -2475);
WIRE 16 -1 (-11050 -2525)(-11275 -2525);
WIRE 16 -1 (-11275 -2575)(-11275 -2525);
WIRE 16 -1 (-11050 -2575)(-11275 -2575);
WIRE 16 -1 (-11050 -1625)(-12400 -1625);
FORCEPROP 2 LAST SIG_NAME FM_SCM_PRSNT1_N
J 0
(-12310 -1615);
DISPLAY 0.638298 (-12310 -1615);
PAINT WHITE (-12310 -1615);
WIRE 16 -1 (-13225 -1575)(-11050 -1575);
FORCEPROP 2 LAST SIG_NAME IRQ0_A57
J 0
(-12310 -1565);
DISPLAY 0.638298 (-12310 -1565);
PAINT WHITE (-12310 -1565);
WIRE 16 -1 (-14525 -1475)(-11050 -1475);
FORCEPROP 2 LAST SIG_NAME FM_BMC_INTRUDER_N
J 0
(-12310 -1465);
DISPLAY 0.638298 (-12310 -1465);
PAINT RED (-12310 -1465);
WIRE 16 -1 (-11050 -1425)(-13225 -1425);
FORCEPROP 2 LAST SIG_NAME ROT_P1_RST_IND_N
J 0
(-12310 -1415);
DISPLAY 0.638298 (-12310 -1415);
PAINT WHITE (-12310 -1415);
WIRE 16 -1 (-12975 -925)(-11050 -925);
FORCEPROP 2 LAST SIG_NAME FM_JTAG_BMC_MUX_SEL_FROM_BMC_R2
J 0
(-12310 -915);
DISPLAY 0.638298 (-12310 -915);
PAINT WHITE (-12310 -915);
WIRE 16 2175 (-13575 -475)(-12900 -475);
WIRE 16 2175 (-12900 -475)(-12900 -650);
WIRE 16 2175 (-13575 -475)(-13575 -650);
WIRE 16 2175 (-13575 -650)(-12900 -650);
WIRE 16 -1 (-13375 75)(-14525 75);
FORCEPROP 0 LAST SIG_NAME SMB_1_PLD_3V3AUX_SCL
J 0
(-14435 85);
DISPLAY 0.680851 (-14435 85);
PAINT WHITE (-14435 85);
WIRE 16 -1 (-11050 125)(-13175 125);
FORCEPROP 0 LAST SIG_NAME SMB_SML0_3V3AUX_SDA_R1
J 0
(-12310 135);
DISPLAY 0.680851 (-12310 135);
PAINT WHITE (-12310 135);
WIRE 16 -1 (-12400 -1775)(-11050 -1775);
FORCEPROP 2 LAST SIG_NAME USB3_PCH_RX_DN<4>
J 0
(-12310 -1765);
DISPLAY 0.680851 (-12310 -1765);
PAINT WHITE (-12310 -1765);
WIRE 16 -1 (-11050 -1925)(-12400 -1925);
FORCEPROP 2 LAST SIG_NAME TP_PCIE_HPM_RXN[1]
J 0
(-12310 -1915);
DISPLAY 0.638298 (-12310 -1915);
PAINT WHITE (-12310 -1915);
WIRE 16 -1 (-11050 -2175)(-12400 -2175);
FORCEPROP 2 LAST SIG_NAME CLK_100M_BMC_RC_DP
J 0
(-12310 -2165);
DISPLAY 0.638298 (-12310 -2165);
PAINT WHITE (-12310 -2165);
WIRE 16 -1 (-9750 2025)(-9550 2025);
WIRE 16 -1 (-9750 1875)(-9550 1875);
WIRE 16 -1 (-9550 1875)(-9550 2025);
WIRE 16 -1 (-9750 1725)(-9550 1725);
WIRE 16 -1 (-9550 1875)(-9550 1725);
WIRE 16 -1 (-9750 925)(-9550 925);
WIRE 16 -1 (-9550 1725)(-9550 925);
WIRE 16 -1 (-9750 575)(-9550 575);
WIRE 16 -1 (-9550 575)(-9550 925);
WIRE 16 -1 (-9750 125)(-9550 125);
WIRE 16 -1 (-9550 125)(-9550 575);
WIRE 16 -1 (-9750 -325)(-9550 -325);
WIRE 16 -1 (-9550 -325)(-9550 125);
WIRE 16 -1 (-9750 -575)(-9550 -575);
WIRE 16 -1 (-9550 -575)(-9550 -325);
WIRE 16 -1 (-9750 -1225)(-9550 -1225);
WIRE 16 -1 (-9550 -575)(-9550 -1225);
WIRE 16 -1 (-9750 -1375)(-9550 -1375);
WIRE 16 -1 (-9550 -1375)(-9550 -1225);
WIRE 16 -1 (-9750 -1525)(-9550 -1525);
WIRE 16 -1 (-9550 -1525)(-9550 -1375);
WIRE 16 -1 (-9750 -1675)(-9550 -1675);
WIRE 16 -1 (-9550 -1675)(-9550 -1525);
WIRE 16 -1 (-9750 -1825)(-9550 -1825);
WIRE 16 -1 (-9550 -1825)(-9550 -1675);
WIRE 16 -1 (-9750 -1975)(-9550 -1975);
WIRE 16 -1 (-9550 -1975)(-9550 -1825);
WIRE 16 -1 (-9750 -2125)(-9550 -2125);
WIRE 16 -1 (-9550 -2125)(-9550 -1975);
WIRE 16 -1 (-9550 -2275)(-9550 -2125);
WIRE 16 -1 (-9750 -2275)(-9550 -2275);
WIRE 16 -1 (-9750 -1775)(-8400 -1775);
FORCEPROP 2 LAST SIG_NAME USB3_PCH_TX_BUF_C_DN<4>
J 0
(-9435 -1765);
DISPLAY 0.553191 (-9435 -1765);
PAINT WHITE (-9435 -1765);
WIRE 16 -1 (-9750 -1725)(-8400 -1725);
FORCEPROP 2 LAST SIG_NAME USB3_PCH_TX_BUF_C_DP<4>
J 0
(-9435 -1715);
DISPLAY 0.553191 (-9435 -1715);
PAINT WHITE (-9435 -1715);
WIRE 16 -1 (-8400 -1625)(-9750 -1625);
FORCEPROP 2 LAST SIG_NAME USB2_HUB_2_BUF_EXT_DN
J 0
(-9435 -1615);
DISPLAY 0.638298 (-9435 -1615);
PAINT WHITE (-9435 -1615);
WIRE 16 -1 (-8400 -1575)(-9750 -1575);
FORCEPROP 2 LAST SIG_NAME USB2_HUB_2_BUF_EXT_DP
J 0
(-9435 -1565);
DISPLAY 0.638298 (-9435 -1565);
PAINT WHITE (-9435 -1565);
WIRE 16 -1 (-8400 -1425)(-9750 -1425);
FORCEPROP 2 LAST SIG_NAME USB2_8_DP
J 0
(-9435 -1415);
DISPLAY 0.638298 (-9435 -1415);
PAINT WHITE (-9435 -1415);
WIRE 16 -1 (-11050 1275)(-13175 1275);
FORCEPROP 2 LAST SIG_NAME SMB_HOST_3V3AUX_SCL_R0
J 0
(-12310 1285);
DISPLAY 0.638298 (-12310 1285);
PAINT WHITE (-12310 1285);
WIRE 16 -1 (-11050 1325)(-13175 1325);
FORCEPROP 2 LAST SIG_NAME SMB_OCP_SFF_3V3AUX_SDA_R0
J 0
(-12310 1335);
DISPLAY 0.638298 (-12310 1335);
PAINT WHITE (-12310 1335);
WIRE 16 -1 (-6775 1525)(-7700 1525);
FORCEPROP 2 LAST SIG_NAME FM_SOL_UART_CH_SEL
J 0
(-7385 1535);
DISPLAY 0.638298 (-7385 1535);
PAINT RED (-7385 1535);
WIRE 16 -1 (-8075 1775)(-7375 1775);
FORCEPROP 0 LAST CDS_PHYS_NET_NAME USB2_7_DN
J 0
(-7985 1809);
PAINT MONO (-7985 1809);
DISPLAY INVISIBLE (-7985 1809);
FORCEPROP 2 LAST SIG_NAME USB2_7_DN
J 0
(-7735 1785);
DISPLAY 0.638298 (-7735 1785);
PAINT WHITE (-7735 1785);
WIRE 16 -1 (-8075 1825)(-7375 1825);
FORCEPROP 0 LAST CDS_PHYS_NET_NAME USB2_7_DP
J 0
(-7985 1859);
PAINT MONO (-7985 1859);
DISPLAY INVISIBLE (-7985 1859);
FORCEPROP 2 LAST SIG_NAME USB2_7_DP
J 0
(-7735 1835);
DISPLAY 0.638298 (-7735 1835);
PAINT WHITE (-7735 1835);
WIRE 16 -1 (-8225 2075)(-9750 2075);
FORCEPROP 2 LAST SIG_NAME PRSNT0_N
J 0
(-9435 2085);
DISPLAY 0.638298 (-9435 2085);
PAINT WHITE (-9435 2085);
WIRE 16 -1 (-8225 2075)(-8225 2425);
WIRE 16 -1 (-8225 2425)(-7625 2425);
WIRE 16 -1 (-7625 2350)(-7625 2425);
WIRE 16 -1 (-8400 525)(-9750 525);
FORCEPROP 0 LAST CDS_PHYS_NET_NAME CLK_50M_RMII_BMC_OCP
J 0
(-9660 565);
PAINT MONO (-9660 565);
DISPLAY INVISIBLE (-9660 565);
FORCEPROP 2 LAST SIG_NAME CLK_50M_RMII_BMC_OCP
J 0
(-9435 535);
DISPLAY 0.638298 (-9435 535);
PAINT WHITE (-9435 535);
WIRE 16 -1 (-8400 425)(-9750 425);
FORCEPROP 0 LAST CDS_PHYS_NET_NAME RMII_BMC_OCP_TX_EN
J 0
(-9660 465);
PAINT MONO (-9660 465);
DISPLAY INVISIBLE (-9660 465);
FORCEPROP 2 LAST SIG_NAME RMII_BMC_OCP_TX_EN
J 0
(-9435 435);
DISPLAY 0.638298 (-9435 435);
PAINT WHITE (-9435 435);
WIRE 16 -1 (-8400 75)(-9750 75);
FORCEPROP 2 LAST SIG_NAME PECI_BMC
J 0
(-9435 85);
DISPLAY 0.638298 (-9435 85);
PAINT WHITE (-9435 85);
WIRE 16 -1 (-8400 25)(-9750 25);
FORCEPROP 2 LAST SIG_NAME PVCCIO_PECI_BMC
J 0
(-9435 35);
DISPLAY 0.638298 (-9435 35);
PAINT WHITE (-9435 35);
WIRE 16 -1 (-8400 175)(-9750 175);
FORCEPROP 2 LAST SIG_NAME RMII_OCP_BMC_RXD_1
J 0
(-9435 185);
DISPLAY 0.638298 (-9435 185);
PAINT WHITE (-9435 185);
WIRE 16 -1 (-8400 275)(-9750 275);
FORCEPROP 0 LAST CDS_PHYS_NET_NAME RMII_BMC_OCP_RX_ER
J 0
(-9660 315);
PAINT MONO (-9660 315);
DISPLAY INVISIBLE (-9660 315);
FORCEPROP 2 LAST SIG_NAME RMII_BMC_OCP_RX_ER
J 0
(-9435 285);
DISPLAY 0.638298 (-9435 285);
PAINT WHITE (-9435 285);
WIRE 16 -1 (-8400 325)(-9750 325);
FORCEPROP 2 LAST SIG_NAME RMII_BMC_OCP_TXD_1
J 0
(-9435 335);
DISPLAY 0.638298 (-9435 335);
PAINT WHITE (-9435 335);
WIRE 16 -1 (-8400 375)(-9750 375);
FORCEPROP 2 LAST SIG_NAME RMII_BMC_OCP_TXD_0
J 0
(-9435 385);
DISPLAY 0.638298 (-9435 385);
PAINT WHITE (-9435 385);
WIRE 16 -1 (-9750 -125)(-8400 -125);
FORCEPROP 2 LAST SIG_NAME SGPIO_DO_0
J 0
(-9435 -115);
DISPLAY 0.638298 (-9435 -115);
PAINT WHITE (-9435 -115);
WIRE 16 -1 (-9750 -225)(-8400 -225);
FORCEPROP 2 LAST SIG_NAME SGPIO_DI_0
J 0
(-9435 -215);
DISPLAY 0.638298 (-9435 -215);
PAINT WHITE (-9435 -215);
WIRE 16 -1 (-9750 -175)(-8400 -175);
FORCEPROP 2 LAST SIG_NAME SGPIO_CLK_0
J 0
(-9435 -165);
DISPLAY 0.638298 (-9435 -165);
PAINT WHITE (-9435 -165);
WIRE 16 -1 (-8400 1325)(-9750 1325);
FORCEPROP 2 LAST SIG_NAME ESPI_HOST_LPC_BMC_LFRAME_N
J 0
(-9435 1335);
DISPLAY 0.638298 (-9435 1335);
PAINT WHITE (-9435 1335);
WIRE 16 -1 (-9750 1575)(-8400 1575);
FORCEPROP 0 LAST CDS_PHYS_NET_NAME H_CPU_CATERR_LVC2_BMC_N
J 0
(-9725 1617);
PAINT MONO (-9725 1617);
DISPLAY INVISIBLE (-9725 1617);
FORCEPROP 0 LAST SIG_NAME H_CPU_CATERR_LVC2_BMC_N
J 0
(-9435 1585);
DISPLAY 0.680851 (-9435 1585);
PAINT RED (-9435 1585);
WIRE 16 -1 (-8400 1625)(-9750 1625);
FORCEPROP 0 LAST CDS_PHYS_NET_NAME SPI_TPM_CS_N
J 0
(-9660 1659);
PAINT MONO (-9660 1659);
DISPLAY INVISIBLE (-9660 1659);
FORCEPROP 2 LAST SIG_NAME SPI_TPM_CS_N
J 0
(-9435 1635);
DISPLAY 0.638298 (-9435 1635);
PAINT RED (-9435 1635);
WIRE 16 -1 (-8400 1375)(-9750 1375);
FORCEPROP 2 LAST SIG_NAME ESPI_HOST_LPC_BMC_CLK
J 0
(-9435 1385);
DISPLAY 0.638298 (-9435 1385);
PAINT WHITE (-9435 1385);
WIRE 16 -1 (-8400 1975)(-9750 1975);
FORCEPROP 0 LAST CDS_PHYS_NET_NAME UART_BMC_BIC_TX
J 0
(-9660 2009);
PAINT MONO (-9660 2009);
DISPLAY INVISIBLE (-9660 2009);
FORCEPROP 2 LAST SIG_NAME UART_BMC_BIC_TX
J 0
(-9435 1985);
DISPLAY 0.638298 (-9435 1985);
PAINT WHITE (-9435 1985);
WIRE 16 -1 (-8400 1925)(-9750 1925);
FORCEPROP 0 LAST CDS_PHYS_NET_NAME UART_BMC_BIC_BUF_RX
J 0
(-9660 1959);
PAINT MONO (-9660 1959);
DISPLAY INVISIBLE (-9660 1959);
FORCEPROP 2 LAST SIG_NAME UART_BMC_BIC_BUF_RX
J 0
(-9435 1935);
DISPLAY 0.638298 (-9435 1935);
PAINT WHITE (-9435 1935);
WIRE 16 -1 (-9750 1825)(-8275 1825);
FORCEPROP 0 LAST CDS_PHYS_NET_NAME USB2_7_R_DP
J 0
(-9660 1859);
PAINT MONO (-9660 1859);
DISPLAY INVISIBLE (-9660 1859);
FORCEPROP 2 LAST SIG_NAME USB2_7_R_DP
J 0
(-9435 1835);
DISPLAY 0.638298 (-9435 1835);
PAINT WHITE (-9435 1835);
WIRE 16 -1 (-9750 675)(-8400 675);
FORCEPROP 2 LAST SIG_NAME SPI_SYS_WP_IO2
J 0
(-9435 685);
DISPLAY 0.638298 (-9435 685);
PAINT WHITE (-9435 685);
WIRE 16 -1 (-9750 725)(-8400 725);
FORCEPROP 2 LAST SIG_NAME SPI_SYS_MISO
J 0
(-9435 735);
DISPLAY 0.638298 (-9435 735);
PAINT WHITE (-9435 735);
WIRE 16 -1 (-9750 775)(-8400 775);
FORCEPROP 2 LAST SIG_NAME SPI_SYS_MOSI
J 0
(-9435 785);
DISPLAY 0.638298 (-9435 785);
PAINT WHITE (-9435 785);
WIRE 16 -1 (-8400 825)(-9750 825);
FORCEPROP 2 LAST SIG_NAME SPI_SYS_CS0_N
J 0
(-9435 835);
DISPLAY 0.638298 (-9435 835);
PAINT WHITE (-9435 835);
WIRE 16 -1 (-9750 875)(-8400 875);
FORCEPROP 2 LAST SIG_NAME SPI_SYS_CLK
J 0
(-9435 885);
DISPLAY 0.638298 (-9435 885);
PAINT WHITE (-9435 885);
WIRE 16 -1 (-8400 1025)(-9750 1025);
FORCEPROP 2 LAST SIG_NAME ESPI_LPC_LAD0_IO3
J 0
(-9435 1035);
DISPLAY 0.638298 (-9435 1035);
PAINT WHITE (-9435 1035);
WIRE 16 -1 (-8400 1075)(-9750 1075);
FORCEPROP 2 LAST SIG_NAME ESPI_LPC_LAD0_IO2
J 0
(-9435 1085);
DISPLAY 0.638298 (-9435 1085);
PAINT WHITE (-9435 1085);
WIRE 16 -1 (-8400 1175)(-9750 1175);
FORCEPROP 2 LAST SIG_NAME ESPI_LPC_LAD0_IO0
J 0
(-9435 1185);
DISPLAY 0.638298 (-9435 1185);
PAINT WHITE (-9435 1185);
WIRE 16 -1 (-8400 1225)(-9750 1225);
FORCEPROP 2 LAST SIG_NAME ESPI_BMC_LPC_RST_N
J 0
(-9435 1235);
DISPLAY 0.638298 (-9435 1235);
PAINT WHITE (-9435 1235);
WIRE 16 -1 (-8400 1675)(-9750 1675);
FORCEPROP 0 LAST CDS_PHYS_NET_NAME RST_SRST_PLD_BMC_N
J 0
(-9660 1709);
PAINT MONO (-9660 1709);
DISPLAY INVISIBLE (-9660 1709);
FORCEPROP 2 LAST SIG_NAME RST_SRST_PLD_BMC_N
J 0
(-9435 1685);
DISPLAY 0.638298 (-9435 1685);
PAINT WHITE (-9435 1685);
WIRE 16 -1 (-9550 2125)(-9750 2125);
WIRE 16 -1 (-9750 2175)(-9550 2175);
WIRE 16 -1 (-9550 2175)(-9550 2125);
WIRE 16 -1 (-8400 475)(-9750 475);
FORCEPROP 0 LAST CDS_PHYS_NET_NAME RMII_OCP_BMC_CRSDV
J 0
(-9660 515);
PAINT MONO (-9660 515);
DISPLAY INVISIBLE (-9660 515);
FORCEPROP 2 LAST SIG_NAME RMII_OCP_BMC_CRSDV
J 0
(-9435 485);
DISPLAY 0.638298 (-9435 485);
PAINT WHITE (-9435 485);
WIRE 16 -1 (-9750 625)(-8400 625);
FORCEPROP 2 LAST SIG_NAME SPI_SYS_HOLD_IO3
J 0
(-9435 635);
DISPLAY 0.638298 (-9435 635);
PAINT WHITE (-9435 635);
WIRE 16 -1 (-8400 975)(-9750 975);
FORCEPROP 2 LAST SIG_NAME FM_LPC_ESPI_SEL
J 0
(-9435 985);
DISPLAY 0.638298 (-9435 985);
PAINT WHITE (-9435 985);
WIRE 16 -1 (-8400 1125)(-9750 1125);
FORCEPROP 2 LAST SIG_NAME ESPI_LPC_LAD0_IO1
J 0
(-9435 1135);
DISPLAY 0.638298 (-9435 1135);
PAINT WHITE (-9435 1135);
WIRE 16 -1 (-8400 1275)(-9750 1275);
FORCEPROP 2 LAST SIG_NAME IRQ_ESPI_LPC_SERIRQ_ALERT_R_N
J 0
(-9435 1285);
DISPLAY 0.638298 (-9435 1285);
PAINT WHITE (-9435 1285);
WIRE 16 -1 (-9750 1775)(-8275 1775);
FORCEPROP 0 LAST CDS_PHYS_NET_NAME USB2_7_R_DN
J 0
(-9660 1809);
PAINT MONO (-9660 1809);
DISPLAY INVISIBLE (-9660 1809);
FORCEPROP 2 LAST SIG_NAME USB2_7_R_DN
J 0
(-9435 1785);
DISPLAY 0.638298 (-9435 1785);
PAINT WHITE (-9435 1785);
WIRE 16 -1 (-7900 1525)(-9750 1525);
FORCEPROP 2 LAST SIG_NAME FM_SOL_UART_CH_SEL_R
J 0
(-9435 1535);
DISPLAY 0.638298 (-9435 1535);
PAINT RED (-9435 1535);
WIRE 16 -1 (-9750 -475)(-8400 -475);
FORCEPROP 2 LAST SIG_NAME SGPIO_DI_1
J 0
(-9435 -465);
DISPLAY 0.638298 (-9435 -465);
PAINT WHITE (-9435 -465);
WIRE 16 -1 (-8400 -425)(-9750 -425);
FORCEPROP 2 LAST SIG_NAME SGPIO_CLK_1
J 0
(-9435 -415);
DISPLAY 0.638298 (-9435 -415);
PAINT WHITE (-9435 -415);
WIRE 16 -1 (-8400 -375)(-9750 -375);
FORCEPROP 0 LAST CDS_PHYS_NET_NAME SGPIO_DO_1
J 0
(-9660 -341);
PAINT MONO (-9660 -341);
DISPLAY INVISIBLE (-9660 -341);
FORCEPROP 2 LAST SIG_NAME SGPIO_DO_1
J 0
(-9435 -365);
DISPLAY 0.638298 (-9435 -365);
PAINT WHITE (-9435 -365);
WIRE 16 -1 (-9750 -275)(-8400 -275);
FORCEPROP 2 LAST SIG_NAME SGPIO_LD_0
J 0
(-9435 -265);
DISPLAY 0.638298 (-9435 -265);
PAINT WHITE (-9435 -265);
WIRE 16 -1 (-8400 225)(-9750 225);
FORCEPROP 2 LAST SIG_NAME RMII_OCP_BMC_RXD_0
J 0
(-9435 235);
DISPLAY 0.638298 (-9435 235);
PAINT WHITE (-9435 235);
WIRE 16 -1 (-11050 2125)(-11275 2125);
WIRE 16 -1 (-11050 1675)(-12400 1675);
FORCEPROP 2 LAST SIG_NAME I3C_SPD_DDREFGH_CPU1_BMC_R_SCL
J 0
(-12310 1685);
DISPLAY 0.638298 (-12310 1685);
PAINT WHITE (-12310 1685);
WIRE 16 -1 (-12400 1875)(-11050 1875);
FORCEPROP 2 LAST SIG_NAME I3C_SPD_DDREFGH_CPU0_BMC_R_SCL
J 0
(-12310 1885);
DISPLAY 0.638298 (-12310 1885);
PAINT WHITE (-12310 1885);
WIRE 16 -1 (-12400 1925)(-11050 1925);
FORCEPROP 0 LAST CDS_PHYS_NET_NAME I3C_SPD_DDRABCD_CPU0_BMC_R_SDA
J 0
(-12085 1965);
PAINT MONO (-12085 1965);
DISPLAY INVISIBLE (-12085 1965);
FORCEPROP 2 LAST SIG_NAME I3C_SPD_DDRABCD_CPU0_BMC_R_SDA
J 0
(-12310 1935);
DISPLAY 0.638298 (-12310 1935);
PAINT WHITE (-12310 1935);
WIRE 16 -1 (-12400 1975)(-11050 1975);
FORCEPROP 0 LAST CDS_PHYS_NET_NAME I3C_SPD_DDRABCD_CPU0_BMC_R_SCL
J 0
(-12085 2015);
PAINT MONO (-12085 2015);
DISPLAY INVISIBLE (-12085 2015);
FORCEPROP 2 LAST SIG_NAME I3C_SPD_DDRABCD_CPU0_BMC_R_SCL
J 0
(-12310 1985);
DISPLAY 0.638298 (-12310 1985);
PAINT WHITE (-12310 1985);
WIRE 16 -1 (-11050 1625)(-12400 1625);
FORCEPROP 2 LAST SIG_NAME I3C_SPD_DDREFGH_CPU1_BMC_R_SDA
J 0
(-12310 1635);
DISPLAY 0.638298 (-12310 1635);
PAINT WHITE (-12310 1635);
WIRE 16 -1 (-12400 1725)(-11050 1725);
FORCEPROP 2 LAST SIG_NAME I3C_SPD_DDRABCD_CPU1_BMC_R_SDA
J 0
(-12310 1735);
DISPLAY 0.638298 (-12310 1735);
PAINT WHITE (-12310 1735);
WIRE 16 -1 (-12400 1825)(-11050 1825);
FORCEPROP 2 LAST SIG_NAME I3C_SPD_DDREFGH_CPU0_BMC_R_SDA
J 0
(-12310 1835);
DISPLAY 0.638298 (-12310 1835);
PAINT WHITE (-12310 1835);
WIRE 16 -1 (-12400 1775)(-11050 1775);
FORCEPROP 2 LAST SIG_NAME I3C_SPD_DDRABCD_CPU1_BMC_R_SCL
J 0
(-12310 1785);
DISPLAY 0.638298 (-12310 1785);
PAINT WHITE (-12310 1785);
WIRE 16 -1 (-11050 1225)(-13175 1225);
FORCEPROP 2 LAST SIG_NAME SMB_HOST_3V3AUX_SDA_R0
J 0
(-12310 1235);
DISPLAY 0.638298 (-12310 1235);
PAINT WHITE (-12310 1235);
WIRE 16 -1 (-11050 1175)(-13175 1175);
FORCEPROP 2 LAST SIG_NAME SMB_VR_3V3AUX_SCL_R0
J 0
(-12310 1185);
DISPLAY 0.638298 (-12310 1185);
PAINT WHITE (-12310 1185);
WIRE 16 -1 (-11050 1125)(-13175 1125);
FORCEPROP 2 LAST SIG_NAME SMB_VR_3V3AUX_SDA_R0
J 0
(-12310 1135);
DISPLAY 0.638298 (-12310 1135);
PAINT WHITE (-12310 1135);
WIRE 16 -1 (-11050 1075)(-13175 1075);
FORCEPROP 2 LAST SIG_NAME SMB_SML1_PMBUS_3V3AUX_PCH_SCL_R0
J 0
(-12310 1085);
DISPLAY 0.638298 (-12310 1085);
PAINT WHITE (-12310 1085);
WIRE 16 -1 (-11050 1025)(-13175 1025);
FORCEPROP 2 LAST SIG_NAME SMB_SML1_PMBUS_3V3AUX_PCH_SDA_R0
J 0
(-12310 1035);
DISPLAY 0.638298 (-12310 1035);
PAINT WHITE (-12310 1035);
WIRE 16 -1 (-11050 975)(-12400 975);
FORCEPROP 2 LAST SIG_NAME I3C_BMC_SWB_SCL
J 0
(-12310 985);
DISPLAY 0.638298 (-12310 985);
PAINT WHITE (-12310 985);
WIRE 16 -1 (-11050 925)(-12400 925);
FORCEPROP 2 LAST SIG_NAME I3C_BMC_SWB_SDA
J 0
(-12310 935);
DISPLAY 0.638298 (-12310 935);
PAINT WHITE (-12310 935);
WIRE 16 -1 (-11050 875)(-13175 875);
FORCEPROP 2 LAST SIG_NAME SMB_OCP_V3_2_3V3AUX_SCL_R0
J 0
(-12310 885);
DISPLAY 0.638298 (-12310 885);
PAINT WHITE (-12310 885);
WIRE 16 -1 (-11050 725)(-13175 725);
FORCEPROP 2 LAST SIG_NAME CLK_100M_BMC_P3E_DP_R
J 0
(-12310 735);
DISPLAY 0.638298 (-12310 735);
PAINT WHITE (-12310 735);
WIRE 16 -1 (-11050 425)(-12400 425);
FORCEPROP 2 LAST SIG_NAME P3E_PCH_BMC_RX_DP
J 0
(-12310 435);
DISPLAY 0.638298 (-12310 435);
PAINT WHITE (-12310 435);
WIRE 16 -1 (-11050 375)(-12400 375);
FORCEPROP 2 LAST SIG_NAME P3E_PCH_BMC_RX_DN
J 0
(-12310 385);
DISPLAY 0.638298 (-12310 385);
PAINT WHITE (-12310 385);
WIRE 16 -1 (-12400 275)(-11050 275);
FORCEPROP 2 LAST SIG_NAME SMB_PCIE0_3V3AUX_SCL
J 0
(-12310 285);
DISPLAY 0.638298 (-12310 285);
PAINT WHITE (-12310 285);
WIRE 16 -1 (-11050 -375)(-12400 -375);
FORCEPROP 2 LAST SIG_NAME JTAG_BMC_TCK
J 0
(-12310 -365);
DISPLAY 0.638298 (-12310 -365);
PAINT WHITE (-12310 -365);
WIRE 16 -1 (-12400 575)(-11050 575);
FORCEPROP 2 LAST SIG_NAME P3E_PCH_BMC_TX_C_DP
J 0
(-12310 585);
DISPLAY 0.638298 (-12310 585);
PAINT WHITE (-12310 585);
WIRE 16 -1 (-12400 525)(-11050 525);
FORCEPROP 2 LAST SIG_NAME P3E_PCH_BMC_TX_C_DN
J 0
(-12310 535);
DISPLAY 0.638298 (-12310 535);
PAINT WHITE (-12310 535);
WIRE 16 -1 (-11050 675)(-13175 675);
FORCEPROP 2 LAST SIG_NAME CLK_100M_BMC_P3E_DN_R
J 0
(-12310 685);
DISPLAY 0.638298 (-12310 685);
PAINT WHITE (-12310 685);
WIRE 16 -1 (-11050 825)(-13175 825);
FORCEPROP 2 LAST SIG_NAME SMB_OCP_V3_2_3V3AUX_SDA_R0
J 0
(-12310 835);
DISPLAY 0.638298 (-12310 835);
PAINT WHITE (-12310 835);
WIRE 16 -1 (-12400 225)(-11050 225);
FORCEPROP 2 LAST SIG_NAME SMB_PCIE0_3V3AUX_SDA
J 0
(-12310 235);
DISPLAY 0.638298 (-12310 235);
PAINT WHITE (-12310 235);
WIRE 16 -1 (-11050 175)(-13175 175);
FORCEPROP 0 LAST SIG_NAME SMB_SML0_3V3AUX_SCL_R1
J 0
(-12310 185);
DISPLAY 0.680851 (-12310 185);
PAINT WHITE (-12310 185);
WIRE 16 -1 (-11050 75)(-13175 75);
FORCEPROP 0 LAST SIG_NAME SMB_1_PLD_3V3AUX_SCL_R3
J 0
(-12310 85);
DISPLAY 0.680851 (-12310 85);
PAINT WHITE (-12310 85);
WIRE 16 -1 (-11050 -475)(-12400 -475);
FORCEPROP 2 LAST SIG_NAME JTAG_BMC_TDI
J 0
(-12310 -465);
DISPLAY 0.638298 (-12310 -465);
PAINT WHITE (-12310 -465);
WIRE 16 -1 (-11050 25)(-13175 25);
FORCEPROP 0 LAST SIG_NAME SMB_1_PLD_3V3AUX_SDA_R3
J 0
(-12310 35);
DISPLAY 0.680851 (-12310 35);
PAINT WHITE (-12310 35);
WIRE 16 -1 (-11050 1525)(-12400 1525);
FORCEPROP 2 LAST SIG_NAME VIRTUAL_RESEAT
J 0
(-12310 1535);
DISPLAY 0.638298 (-12310 1535);
PAINT WHITE (-12310 1535);
WIRE 16 -1 (-11050 1375)(-13175 1375);
FORCEPROP 2 LAST SIG_NAME SMB_OCP_SFF_3V3AUX_SCL_R0
J 0
(-12310 1385);
DISPLAY 0.638298 (-12310 1385);
PAINT WHITE (-12310 1385);
WIRE 16 -1 (-11050 -125)(-12400 -125);
FORCEPROP 0 LAST SIG_NAME SMB_FAN_3V3AUX_SCL
J 0
(-12310 -115);
DISPLAY 0.680851 (-12310 -115);
PAINT WHITE (-12310 -115);
WIRE 16 -1 (-11050 -175)(-12400 -175);
FORCEPROP 0 LAST SIG_NAME SMB_FAN_3V3AUX_SDA
J 0
(-12310 -165);
DISPLAY 0.680851 (-12310 -165);
PAINT WHITE (-12310 -165);
WIRE 16 -1 (-11050 -425)(-12400 -425);
FORCEPROP 2 LAST SIG_NAME JTAG_BMC_TMS
J 0
(-12310 -415);
DISPLAY 0.638298 (-12310 -415);
PAINT WHITE (-12310 -415);
WIRE 16 -1 (-11050 -225)(-13200 -225);
FORCEPROP 0 LAST SIG_NAME SMB_PCIE2_3V3AUX_SCL_R0
J 0
(-12310 -215);
DISPLAY 0.680851 (-12310 -215);
PAINT WHITE (-12310 -215);
WIRE 16 2175 (-13575 -150)(-12900 -150);
WIRE 16 2175 (-12900 -150)(-12900 -325);
WIRE 16 2175 (-13575 -150)(-13575 -325);
WIRE 16 2175 (-13575 -325)(-12900 -325);
WIRE 16 -1 (-13375 1125)(-14500 1125);
FORCEPROP 0 LAST SIG_NAME SMB_VR_SENSOR_3V3AUX_SDA
J 0
(-14410 1135);
DISPLAY 0.553191 (-14410 1135);
PAINT WHITE (-14410 1135);
WIRE 16 -1 (-13375 1175)(-14500 1175);
FORCEPROP 0 LAST SIG_NAME SMB_VR_SENSOR_3V3AUX_SCL
J 0
(-14410 1185);
DISPLAY 0.553191 (-14410 1185);
PAINT WHITE (-14410 1185);
WIRE 16 -1 (-13375 175)(-14525 175);
FORCEPROP 0 LAST SIG_NAME SMB_SML0_3V3AUX_SCL
J 0
(-14435 185);
DISPLAY 0.680851 (-14435 185);
PAINT WHITE (-14435 185);
WIRE 16 -1 (-13375 825)(-14500 825);
FORCEPROP 0 LAST SIG_NAME SMB_OCP_V3_2_3V3AUX_SDA
J 0
(-14410 835);
DISPLAY 0.553191 (-14410 835);
PAINT WHITE (-14410 835);
WIRE 16 -1 (-13375 725)(-14500 725);
FORCEPROP 2 LAST SIG_NAME CLK_100M_BMC_P3E_DP
J 0
(-14410 735);
DISPLAY 0.638298 (-14410 735);
PAINT WHITE (-14410 735);
WIRE 16 -1 (-13375 675)(-14500 675);
FORCEPROP 2 LAST SIG_NAME CLK_100M_BMC_P3E_DN
J 0
(-14410 685);
DISPLAY 0.638298 (-14410 685);
PAINT WHITE (-14410 685);
WIRE 16 -1 (-13375 25)(-14525 25);
FORCEPROP 0 LAST SIG_NAME SMB_1_PLD_3V3AUX_SDA
J 0
(-14435 35);
DISPLAY 0.680851 (-14435 35);
PAINT WHITE (-14435 35);
WIRE 16 -1 (-13375 875)(-14500 875);
FORCEPROP 0 LAST SIG_NAME SMB_OCP_V3_2_3V3AUX_SCL
J 0
(-14410 885);
DISPLAY 0.553191 (-14410 885);
PAINT WHITE (-14410 885);
WIRE 16 -1 (-13375 1225)(-14500 1225);
FORCEPROP 0 LAST SIG_NAME SMB_HOST_3V3AUX_SDA
J 0
(-14410 1235);
DISPLAY 0.553191 (-14410 1235);
PAINT WHITE (-14410 1235);
WIRE 16 -1 (-13375 1325)(-14475 1325);
FORCEPROP 0 LAST SIG_NAME SMB_OCP_SFF_3V3AUX_SDA
J 0
(-14410 1335);
DISPLAY 0.553191 (-14410 1335);
PAINT WHITE (-14410 1335);
WIRE 16 -1 (-13400 -275)(-14525 -275);
FORCEPROP 0 LAST SIG_NAME SMB_2_BMC_GPU_SDA
J 0
(-14435 -265);
DISPLAY 0.553191 (-14435 -265);
PAINT WHITE (-14435 -265);
WIRE 16 -1 (-13375 125)(-14525 125);
FORCEPROP 0 LAST SIG_NAME SMB_SML0_3V3AUX_SDA
J 0
(-14435 135);
DISPLAY 0.680851 (-14435 135);
PAINT WHITE (-14435 135);
WIRE 16 -1 (-13375 1025)(-14500 1025);
FORCEPROP 0 LAST SIG_NAME SMB_SML1_PMBUS_3V3AUX_PCH_SDA
J 0
(-14410 1035);
DISPLAY 0.553191 (-14410 1035);
PAINT WHITE (-14410 1035);
WIRE 16 -1 (-13375 1375)(-14475 1375);
FORCEPROP 0 LAST SIG_NAME SMB_OCP_SFF_3V3AUX_SCL
J 0
(-14410 1385);
DISPLAY 0.553191 (-14410 1385);
PAINT WHITE (-14410 1385);
WIRE 16 -1 (-13400 -225)(-14525 -225);
FORCEPROP 0 LAST SIG_NAME SMB_2_BMC_GPU_SCL
J 0
(-14435 -215);
DISPLAY 0.553191 (-14435 -215);
PAINT WHITE (-14435 -215);
WIRE 16 -1 (-13650 2375)(-14525 2375);
FORCEPROP 0 LAST CDS_PHYS_NET_NAME PVCCIO_PECI_BMC
J 0
(-14185 2423);
PAINT MONO (-14185 2423);
DISPLAY INVISIBLE (-14185 2423);
FORCEPROP 2 LAST SIG_NAME PVCCIO_PECI_BMC
J 0
(-14160 2385);
DISPLAY 0.638298 (-14160 2385);
PAINT WHITE (-14160 2385);
WIRE 16 -1 (-11050 -525)(-12400 -525);
FORCEPROP 2 LAST SIG_NAME JTAG_BMC_TDO
J 0
(-12310 -515);
DISPLAY 0.638298 (-12310 -515);
PAINT WHITE (-12310 -515);
WIRE 16 -1 (-9750 -525)(-8400 -525);
FORCEPROP 2 LAST SIG_NAME SGPIO_LD_1
J 0
(-9435 -515);
DISPLAY 0.638298 (-9435 -515);
PAINT WHITE (-9435 -515);
WIRE 16 -1 (-7775 -2225)(-6800 -2225);
FORCEPROP 2 LAST SIG_NAME FM_PCH_SPKR
J 0
(-7410 -2215);
DISPLAY 0.638298 (-7410 -2215);
PAINT WHITE (-7410 -2215);
WIRE 16 -1 (-7775 -2175)(-6800 -2175);
FORCEPROP 2 LAST SIG_NAME LED_HDD_ACTIVITY_B_N
J 0
(-7410 -2165);
DISPLAY 0.638298 (-7410 -2165);
PAINT WHITE (-7410 -2165);
WIRE 16 -1 (-6775 -775)(-7700 -775);
FORCEPROP 0 LAST CDS_PHYS_NET_NAME FM_AC_PWR_BTN_R_N
J 0
(-7610 -741);
PAINT MONO (-7610 -741);
DISPLAY INVISIBLE (-7610 -741);
FORCEPROP 2 LAST SIG_NAME FM_AC_PWR_BTN_R_N
J 0
(-7385 -765);
DISPLAY 0.638298 (-7385 -765);
PAINT RED (-7385 -765);
WIRE 16 -1 (-7700 -725)(-6775 -725);
FORCEPROP 2 LAST SIG_NAME P3V_BAT_R
J 0
(-7310 -715);
DISPLAY 0.638298 (-7310 -715);
PAINT WHITE (-7310 -715);
WIRE 16 -1 (-9750 -2225)(-7975 -2225);
FORCEPROP 2 LAST SIG_NAME TP_PCIE_HPM_TXN[3]
J 0
(-9435 -2215);
DISPLAY 0.638298 (-9435 -2215);
PAINT RED (-9435 -2215);
WIRE 16 -1 (-8400 -2075)(-9750 -2075);
FORCEPROP 2 LAST SIG_NAME P2E_MB_BMC_TX_C_DN<0>
J 0
(-9435 -2065);
DISPLAY 0.638298 (-9435 -2065);
PAINT RED (-9435 -2065);
WIRE 16 -1 (-9750 -2175)(-7975 -2175);
FORCEPROP 2 LAST SIG_NAME TP_PCIE_HPM_TXP[3]
J 0
(-9435 -2165);
DISPLAY 0.638298 (-9435 -2165);
PAINT RED (-9435 -2165);
WIRE 16 -1 (-8400 -2025)(-9750 -2025);
FORCEPROP 2 LAST SIG_NAME P2E_MB_BMC_TX_C_DP<0>
J 0
(-9435 -2015);
DISPLAY 0.638298 (-9435 -2015);
PAINT RED (-9435 -2015);
WIRE 16 -1 (-8400 -1875)(-9750 -1875);
FORCEPROP 0 LAST CDS_PHYS_NET_NAME TP_PCIE_HPM_TXP<1>
J 0
(-9660 -1841);
PAINT MONO (-9660 -1841);
DISPLAY INVISIBLE (-9660 -1841);
FORCEPROP 2 LAST SIG_NAME TP_PCIE_HPM_TXP[1]
J 0
(-9435 -1865);
DISPLAY 0.638298 (-9435 -1865);
PAINT WHITE (-9435 -1865);
WIRE 16 -1 (-8400 -1925)(-9750 -1925);
FORCEPROP 0 LAST CDS_PHYS_NET_NAME TP_PCIE_HPM_TXN<1>
J 0
(-9660 -1891);
PAINT MONO (-9660 -1891);
DISPLAY INVISIBLE (-9660 -1891);
FORCEPROP 2 LAST SIG_NAME TP_PCIE_HPM_TXN[1]
J 0
(-9435 -1915);
DISPLAY 0.638298 (-9435 -1915);
PAINT WHITE (-9435 -1915);
WIRE 16 -1 (-8400 -1275)(-9750 -1275);
FORCEPROP 2 LAST SIG_NAME USB2_HOST_BMC_B_DP
J 0
(-9435 -1265);
DISPLAY 0.638298 (-9435 -1265);
PAINT WHITE (-9435 -1265);
WIRE 16 -1 (-8400 -1325)(-9750 -1325);
FORCEPROP 2 LAST SIG_NAME USB2_HOST_BMC_B_DN
J 0
(-9435 -1315);
DISPLAY 0.638298 (-9435 -1315);
PAINT WHITE (-9435 -1315);
WIRE 16 -1 (-8400 -1475)(-9750 -1475);
FORCEPROP 2 LAST SIG_NAME USB2_8_DN
J 0
(-9435 -1465);
DISPLAY 0.638298 (-9435 -1465);
PAINT WHITE (-9435 -1465);
WIRE 16 -1 (-8400 -1175)(-9750 -1175);
FORCEPROP 0 LAST CDS_PHYS_NET_NAME TP_SPI_2_PLD_IO3
J 0
(-9660 -1141);
PAINT MONO (-9660 -1141);
DISPLAY INVISIBLE (-9660 -1141);
FORCEPROP 2 LAST SIG_NAME TP_SPI_2_PLD_IO3
J 0
(-9435 -1165);
DISPLAY 0.638298 (-9435 -1165);
PAINT WHITE (-9435 -1165);
WIRE 16 -1 (-8400 -625)(-9750 -625);
FORCEPROP 0 LAST CDS_PHYS_NET_NAME RST_SGPIO_RESET_N
J 0
(-9660 -585);
PAINT MONO (-9660 -585);
DISPLAY INVISIBLE (-9660 -585);
FORCEPROP 2 LAST SIG_NAME RST_SGPIO_RESET_N
J 0
(-9435 -615);
DISPLAY 0.638298 (-9435 -615);
PAINT WHITE (-9435 -615);
WIRE 16 -1 (-8400 -1125)(-9750 -1125);
FORCEPROP 0 LAST CDS_PHYS_NET_NAME TP_SPI_2_PLD_IO2
J 0
(-9660 -1091);
PAINT MONO (-9660 -1091);
DISPLAY INVISIBLE (-9660 -1091);
FORCEPROP 2 LAST SIG_NAME TP_SPI_2_PLD_IO2
J 0
(-9435 -1115);
DISPLAY 0.638298 (-9435 -1115);
PAINT WHITE (-9435 -1115);
WIRE 16 -1 (-8400 -1075)(-9750 -1075);
FORCEPROP 0 LAST CDS_PHYS_NET_NAME TP_SPI_2_PLD_IO1
J 0
(-9660 -1041);
PAINT MONO (-9660 -1041);
DISPLAY INVISIBLE (-9660 -1041);
FORCEPROP 2 LAST SIG_NAME TP_SPI_2_PLD_IO1
J 0
(-9435 -1065);
DISPLAY 0.638298 (-9435 -1065);
PAINT WHITE (-9435 -1065);
WIRE 16 -1 (-8400 -1025)(-9750 -1025);
FORCEPROP 0 LAST CDS_PHYS_NET_NAME TP_SPI_2_PLD_IO0
J 0
(-9660 -991);
PAINT MONO (-9660 -991);
DISPLAY INVISIBLE (-9660 -991);
FORCEPROP 2 LAST SIG_NAME TP_SPI_2_PLD_IO0
J 0
(-9435 -1015);
DISPLAY 0.638298 (-9435 -1015);
PAINT WHITE (-9435 -1015);
WIRE 16 -1 (-8400 -975)(-9750 -975);
FORCEPROP 0 LAST CDS_PHYS_NET_NAME TP_SPI_2_PLD_CS_N
J 0
(-9660 -941);
PAINT MONO (-9660 -941);
DISPLAY INVISIBLE (-9660 -941);
FORCEPROP 2 LAST SIG_NAME TP_SPI_2_PLD_CS_N
J 0
(-9435 -965);
DISPLAY 0.638298 (-9435 -965);
PAINT WHITE (-9435 -965);
WIRE 16 -1 (-8400 -925)(-9750 -925);
FORCEPROP 0 LAST CDS_PHYS_NET_NAME TP_SPI_2_PLD_CLK
J 0
(-9660 -891);
PAINT MONO (-9660 -891);
DISPLAY INVISIBLE (-9660 -891);
FORCEPROP 2 LAST SIG_NAME TP_SPI_2_PLD_CLK
J 0
(-9435 -915);
DISPLAY 0.638298 (-9435 -915);
PAINT WHITE (-9435 -915);
WIRE 16 -1 (-7900 -775)(-9750 -775);
FORCEPROP 0 LAST CDS_PHYS_NET_NAME FM_AC_PWR_BTN_N
J 0
(-9660 -741);
PAINT MONO (-9660 -741);
DISPLAY INVISIBLE (-9660 -741);
FORCEPROP 2 LAST SIG_NAME FM_AC_PWR_BTN_N
J 0
(-9435 -765);
DISPLAY 0.638298 (-9435 -765);
PAINT RED (-9435 -765);
WIRE 16 -1 (-9750 -725)(-7900 -725);
FORCEPROP 2 LAST SIG_NAME P3V_BAT_R1
J 0
(-9435 -715);
DISPLAY 0.638298 (-9435 -715);
PAINT WHITE (-9435 -715);
WIRE 16 -1 (-8400 -675)(-9750 -675);
FORCEPROP 0 LAST CDS_PHYS_NET_NAME IRQ_SGPIO_INTR_N
J 0
(-9660 -635);
PAINT MONO (-9660 -635);
DISPLAY INVISIBLE (-9660 -635);
FORCEPROP 2 LAST SIG_NAME IRQ_SGPIO_INTR_N
J 0
(-9435 -665);
DISPLAY 0.638298 (-9435 -665);
PAINT WHITE (-9435 -665);
WIRE 16 -1 (-11050 -1875)(-12400 -1875);
FORCEPROP 2 LAST SIG_NAME TP_PCIE_HPM_RXP[1]
J 0
(-12310 -1865);
DISPLAY 0.638298 (-12310 -1865);
PAINT WHITE (-12310 -1865);
WIRE 16 -1 (-11050 -2025)(-12400 -2025);
FORCEPROP 2 LAST SIG_NAME P2E_MB_BMC_RX_BUF_DP<0>
J 0
(-12310 -2015);
DISPLAY 0.638298 (-12310 -2015);
PAINT WHITE (-12310 -2015);
WIRE 16 -1 (-11050 -675)(-13200 -675);
FORCEPROP 2 LAST SIG_NAME SMB_S3M_CPU_3V3AUX_SCL_R0
J 0
(-12310 -665);
DISPLAY 0.638298 (-12310 -665);
PAINT WHITE (-12310 -665);
WIRE 16 -1 (-11050 -625)(-13200 -625);
FORCEPROP 0 LAST SIG_NAME SMB_PCIE3_3V3AUX_SDA_R
J 0
(-12310 -615);
DISPLAY 0.680851 (-12310 -615);
PAINT WHITE (-12310 -615);
WIRE 16 -1 (-11050 -2075)(-12400 -2075);
FORCEPROP 2 LAST SIG_NAME P2E_MB_BMC_RX_BUF_DN<0>
J 0
(-12310 -2065);
DISPLAY 0.638298 (-12310 -2065);
PAINT WHITE (-12310 -2065);
WIRE 16 -1 (-11050 -1325)(-12400 -1325);
FORCEPROP 2 LAST SIG_NAME RST_PLTRST_B_N
J 0
(-12310 -1315);
DISPLAY 0.638298 (-12310 -1315);
PAINT WHITE (-12310 -1315);
WIRE 16 -1 (-14275 -1175)(-11050 -1175);
FORCEPROP 0 LAST CDS_PHYS_NET_NAME PWRGD_SYS_PWROK
J 0
(-13960 -1135);
PAINT MONO (-13960 -1135);
DISPLAY INVISIBLE (-13960 -1135);
FORCEPROP 2 LAST SIG_NAME PWRGD_SYS_PWROK
J 0
(-12310 -1165);
DISPLAY 0.638298 (-12310 -1165);
PAINT WHITE (-12310 -1165);
WIRE 16 -1 (-12400 -1725)(-11050 -1725);
FORCEPROP 2 LAST SIG_NAME USB3_PCH_RX_DP<4>
J 0
(-12310 -1715);
DISPLAY 0.680851 (-12310 -1715);
PAINT WHITE (-12310 -1715);
WIRE 16 -1 (-11050 -2225)(-12400 -2225);
FORCEPROP 2 LAST SIG_NAME CLK_100M_BMC_RC_DN
J 0
(-12310 -2215);
DISPLAY 0.638298 (-12310 -2215);
PAINT WHITE (-12310 -2215);
WIRE 16 -1 (-11050 -975)(-12975 -975);
FORCEPROP 0 LAST CDS_PHYS_NET_NAME PWRGD_PS_PWROK_R
J 0
(-12010 -935);
PAINT MONO (-12010 -935);
DISPLAY INVISIBLE (-12010 -935);
FORCEPROP 2 LAST SIG_NAME PWRGD_PS_PWROK_R
J 0
(-12310 -965);
DISPLAY 0.638298 (-12310 -965);
PAINT WHITE (-12310 -965);
WIRE 16 -1 (-12975 -1025)(-11050 -1025);
FORCEPROP 0 LAST CDS_PHYS_NET_NAME TP_HPM_STBY_EN
J 0
(-12310 -991);
PAINT MONO (-12310 -991);
DISPLAY INVISIBLE (-12310 -991);
FORCEPROP 2 LAST SIG_NAME TP_HPM_STBY_EN
J 0
(-12310 -1015);
DISPLAY 0.638298 (-12310 -1015);
PAINT WHITE (-12310 -1015);
WIRE 16 -1 (-11050 -1075)(-14275 -1075);
FORCEPROP 0 LAST CDS_PHYS_NET_NAME RST_MB_STBY_N
J 0
(-14185 -1041);
PAINT MONO (-14185 -1041);
DISPLAY INVISIBLE (-14185 -1041);
FORCEPROP 2 LAST SIG_NAME RST_MB_STBY_N
J 0
(-12310 -1065);
DISPLAY 0.638298 (-12310 -1065);
PAINT WHITE (-12310 -1065);
WIRE 16 -1 (-12400 -1225)(-11050 -1225);
FORCEPROP 0 LAST CDS_PHYS_NET_NAME JTAG_BMC_DBP_PREQ_N
J 0
(-12085 -1185);
PAINT MONO (-12085 -1185);
DISPLAY INVISIBLE (-12085 -1185);
FORCEPROP 2 LAST SIG_NAME JTAG_BMC_DBP_PREQ_N
J 0
(-12310 -1215);
DISPLAY 0.638298 (-12310 -1215);
PAINT WHITE (-12310 -1215);
WIRE 16 -1 (-12400 -1275)(-11050 -1275);
FORCEPROP 0 LAST CDS_PHYS_NET_NAME JTAG_DBP_BMC_PRDY_N
J 0
(-12085 -1235);
PAINT MONO (-12085 -1235);
DISPLAY INVISIBLE (-12085 -1235);
FORCEPROP 2 LAST SIG_NAME JTAG_DBP_BMC_PRDY_N
J 0
(-12310 -1265);
DISPLAY 0.638298 (-12310 -1265);
PAINT WHITE (-12310 -1265);
WIRE 16 -1 (-13400 -725)(-14525 -725);
FORCEPROP 2 LAST SIG_NAME SMB_S3M_CPU_3V3AUX_SDA
J 0
(-14435 -715);
DISPLAY 0.510638 (-14435 -715);
PAINT WHITE (-14435 -715);
WIRE 16 -1 (-13175 -925)(-14275 -925);
FORCEPROP 2 LAST SIG_NAME FM_JTAG_BMC_MUX_SEL_FROM_BMC_R
J 0
(-14185 -915);
DISPLAY 0.638298 (-14185 -915);
PAINT WHITE (-14185 -915);
WIRE 16 -1 (-13400 -575)(-14525 -575);
FORCEPROP 0 LAST SIG_NAME SMB_1_BMC_GPU_SCL
J 0
(-14435 -565);
DISPLAY 0.553191 (-14435 -565);
PAINT WHITE (-14435 -565);
WIRE 16 -1 (-13400 -625)(-14525 -625);
FORCEPROP 0 LAST SIG_NAME SMB_1_BMC_GPU_SDA
J 0
(-14435 -615);
DISPLAY 0.553191 (-14435 -615);
PAINT WHITE (-14435 -615);
WIRE 16 -1 (-13400 -675)(-14525 -675);
FORCEPROP 2 LAST SIG_NAME SMB_S3M_CPU_3V3AUX_SCL
J 0
(-14435 -665);
DISPLAY 0.510638 (-14435 -665);
PAINT WHITE (-14435 -665);
WIRE 16 -1 (-13175 -975)(-14275 -975);
FORCEPROP 0 LAST CDS_PHYS_NET_NAME PWRGD_PS_PWROK
J 0
(-13585 -933);
PAINT MONO (-13585 -933);
DISPLAY INVISIBLE (-13585 -933);
FORCEPROP 2 LAST SIG_NAME PWRGD_PS_PWROK
J 0
(-14185 -965);
DISPLAY 0.553191 (-14185 -965);
PAINT WHITE (-14185 -965);
WIRE 16 -1 (-13175 -1125)(-14275 -1125);
FORCEPROP 0 LAST CDS_PHYS_NET_NAME FM_BMC_PWRBTN_OUT_N
J 0
(-13585 -1083);
PAINT MONO (-13585 -1083);
DISPLAY INVISIBLE (-13585 -1083);
FORCEPROP 2 LAST SIG_NAME FM_BMC_PWRBTN_OUT_N
J 0
(-14185 -1115);
DISPLAY 0.553191 (-14185 -1115);
PAINT WHITE (-14185 -1115);
WIRE 16 -1 (-14525 -1375)(-13425 -1375);
FORCEPROP 2 LAST SIG_NAME FM_UARTSW_MSB_N
J 0
(-14435 -1365);
DISPLAY 0.680851 (-14435 -1365);
PAINT WHITE (-14435 -1365);
WIRE 16 -1 (-13425 -1425)(-14525 -1425);
FORCEPROP 2 LAST SIG_NAME ROT_P1_RST_IND_N_R
J 0
(-14435 -1415);
DISPLAY 0.638298 (-14435 -1415);
PAINT WHITE (-14435 -1415);
WIRE 16 -1 (-14525 -1525)(-13425 -1525);
FORCEPROP 2 LAST SIG_NAME FM_UARTSW_LSB_N
J 0
(-14435 -1515);
DISPLAY 0.680851 (-14435 -1515);
PAINT WHITE (-14435 -1515);
WIRE 16 2175 (-14900 -2100)(-13575 -2100);
WIRE 16 2175 (-13575 -2100)(-13575 -2700);
WIRE 16 2175 (-14900 -2100)(-14900 -2700);
WIRE 16 2175 (-14900 -2700)(-13575 -2700);
WIRE 16 -1 (-13425 -1575)(-14525 -1575);
FORCEPROP 2 LAST SIG_NAME IRQ_SMI_ACTIVE_BMC_N
J 0
(-14435 -1565);
DISPLAY 0.638298 (-14435 -1565);
PAINT WHITE (-14435 -1565);
WIRE 16 -1 (-14825 -2225)(-14825 -2325);
WIRE 16 -1 (-13975 -2225)(-14825 -2225);
FORCEPROP 0 LAST CDS_PHYS_NET_NAME FM_BMC_INTRUDER_N
J 0
(-14485 -2177);
PAINT MONO (-14485 -2177);
DISPLAY INVISIBLE (-14485 -2177);
FORCEPROP 2 LAST SIG_NAME FM_BMC_INTRUDER_N
J 0
(-14660 -2215);
DISPLAY 0.638298 (-14660 -2215);
PAINT RED (-14660 -2215);
DOT 1 (-11275 -2575);
DOT 1 (-11275 -1825);
DOT 1 (-11275 -2525);
DOT 1 (-11275 -2375);
DOT 1 (-11275 -2125);
DOT 1 (-11275 -2275);
DOT 1 (-11275 -2475);
DOT 1 (-11275 -2425);
DOT 1 (-11275 -1675);
DOT 1 (-11275 -1975);
DOT 1 (-11275 -775);
DOT 1 (-9550 -2275);
DOT 1 (-9550 -2125);
DOT 1 (-9550 -1825);
DOT 1 (-9550 -1975);
DOT 1 (-9550 -1675);
DOT 1 (-9550 -1375);
DOT 1 (-9550 -1525);
DOT 1 (-9550 -1225);
DOT 1 (-9550 -575);
DOT 1 (-14975 2375);
DOT 1 (-11275 325);
DOT 1 (-11275 475);
DOT 1 (-11275 -325);
DOT 1 (-11275 775);
DOT 1 (-11275 625);
DOT 1 (-11275 2025);
DOT 1 (-11275 1575);
DOT 1 (-11275 2175);
DOT 1 (-9550 -325);
DOT 1 (-9550 125);
DOT 1 (-9550 575);
DOT 1 (-9550 925);
DOT 1 (-9550 1725);
DOT 1 (-9550 1875);
DOT 1 (-9550 2175);
FORCENOTE
20230323 ADD R4809 CONNECT TO GND.
(-14825 -2075) 0;
DISPLAY LEFT (-14825 -2075);
DISPLAY 0.680851 (-14825 -2075);
PAINT WHITE (-14825 -2075);
FORCENOTE
SPI FROM SCM TO MB FPGA
(-8325 -1050) 0;
DISPLAY LEFT (-8325 -1050);
DISPLAY 0.638298 (-8325 -1050);
PAINT SKYBLUE (-8325 -1050);
FORCENOTE
20221222 CHANGE R2413,R2414 TO 0 OHM
(-14025 -375) 0;
DISPLAY LEFT (-14025 -375);
DISPLAY 0.680851 (-14025 -375);
PAINT WHITE (-14025 -375);
FORCENOTE
20210705 MODIFY FOR GT
(-13175 2875) 0;
DISPLAY LEFT (-13175 2875);
DISPLAY 1.595745 (-13175 2875);
PAINT PINK (-13175 2875);
FORCENOTE
SPI FROM MB TO SCM_BIOS FLASH
(-7875 750) 0;
DISPLAY LEFT (-7875 750);
DISPLAY 0.638298 (-7875 750);
PAINT SKYBLUE (-7875 750);
FORCENOTE
20221222 CHANGE R2415,R2416 TO 0 OHM
(-14025 -450) 0;
DISPLAY LEFT (-14025 -450);
DISPLAY 0.680851 (-14025 -450);
PAINT WHITE (-14025 -450);
QUIT
